FILE_TYPE = MACRO_DRAWING;
SET COLOR_WIRE YELLOW;
SET COLOR_PROP ORANGE;
SET COLOR_DOT WHITE;
SET COLOR_ARC YELLOW;
SET COLOR_BODY GREEN;
SET COLOR_NOTE PURPLE;
SET PROP_DISPLAY VALUE;
SET PAGE_NUMBER P71;
FORCEADD Q_CAP..1
(-8500 825);
FORCEPROP 1 LAST LOCATION C2262
J 0
(-8450 925);
DISPLAY 0.489362 (-8450 925);
PAINT SKYBLUE (-8450 925);
FORCEPROP 2 LAST $SEC 1
J 0
(-8450 1025);
DISPLAY 0.680851 (-8450 1025);
PAINT MONO (-8450 1025);
DISPLAY INVISIBLE (-8450 1025);
FORCEPROP 2 LAST CDS_SEC 1
J 0
(-8450 1025);
DISPLAY 1.021277 (-8450 1025);
DISPLAY INVISIBLE (-8450 1025);
FORCEPROP 1 LASTPIN (-8500 925) $PN 1
J 0
(-8490 905);
DISPLAY 0.489362 (-8490 905);
FORCEPROP 1 LASTPIN (-8500 725) $PN 2
J 0
(-8490 705);
DISPLAY 0.489362 (-8490 705);
FORCEPROP 1 LAST MATERIAL X6S
J 0
(-8450 725);
DISPLAY 0.489362 (-8450 725);
PAINT SKYBLUE (-8450 725);
FORCEPROP 1 LAST TOLERANCE 20%
J 0
(-8450 775);
DISPLAY 0.489362 (-8450 775);
PAINT SKYBLUE (-8450 775);
FORCEPROP 1 LAST VALUE 22UF
J 0
(-8450 875);
DISPLAY 0.489362 (-8450 875);
PAINT SKYBLUE (-8450 875);
FORCEPROP 1 LAST PART_NUMBER CH622KMEB02
J 0
(-8450 675);
DISPLAY 0.489362 (-8450 675);
PAINT SKYBLUE (-8450 675);
FORCEPROP 1 LAST VOLTAGE 4V
J 0
(-8450 825);
DISPLAY 0.489362 (-8450 825);
PAINT SKYBLUE (-8450 825);
FORCEPROP 1 LAST PACK_TYPE C0402
J 0
(-8450 625);
DISPLAY 0.489362 (-8450 625);
PAINT SKYBLUE (-8450 625);
FORCEPROP 2 LAST CDS_LIB pure_quanta
J 0
(-8500 825);
PAINT MONO (-8500 825);
DISPLAY INVISIBLE (-8500 825);
FORCEPROP 1 LAST PATH I1
J 0
(-8450 975);
DISPLAY 0.978723 (-8450 975);
PAINT WHITE (-8450 975);
DISPLAY INVISIBLE (-8450 975);
FORCEADD UNIVERSAL_POWER..1
(-8525 5175);
FORCEPROP 3 LASTPIN (-8525 5125) SIG_NAME PVDDCR_SOC_P1\g
J 0
(-8515 5135);
DISPLAY 0.659574 (-8515 5135);
PAINT MONO (-8515 5135);
DISPLAY INVISIBLE (-8515 5135);
FORCEPROP 1 LAST HDL_POWER PVDDCR_SOC_P1
J 1
(-8525 5225);
DISPLAY 0.489362 (-8525 5225);
PAINT GREEN (-8525 5225);
FORCEPROP 2 LAST CDS_LIB pure_quanta_power
J 0
(-8525 5175);
DISPLAY INVISIBLE (-8525 5175);
FORCEPROP 1 LAST PATH I10
J 0
(-8475 5200);
DISPLAY 0.872340 (-8475 5200);
PAINT AQUA (-8475 5200);
DISPLAY INVISIBLE (-8475 5200);
FORCEADD Q_CAP..1
(-8050 825);
FORCEPROP 1 LAST LOCATION C2267
J 0
(-8000 925);
DISPLAY 0.489362 (-8000 925);
PAINT SKYBLUE (-8000 925);
FORCEPROP 2 LAST $SEC 1
J 0
(-8000 1025);
DISPLAY 0.680851 (-8000 1025);
PAINT MONO (-8000 1025);
DISPLAY INVISIBLE (-8000 1025);
FORCEPROP 2 LAST CDS_SEC 1
J 0
(-8000 1025);
DISPLAY 1.021277 (-8000 1025);
DISPLAY INVISIBLE (-8000 1025);
FORCEPROP 1 LASTPIN (-8050 925) $PN 1
J 0
(-8040 905);
DISPLAY 0.489362 (-8040 905);
FORCEPROP 1 LASTPIN (-8050 725) $PN 2
J 0
(-8040 705);
DISPLAY 0.489362 (-8040 705);
FORCEPROP 1 LAST MATERIAL X6S
J 0
(-8000 725);
DISPLAY 0.489362 (-8000 725);
PAINT SKYBLUE (-8000 725);
FORCEPROP 1 LAST TOLERANCE 20%
J 0
(-8000 775);
DISPLAY 0.489362 (-8000 775);
PAINT SKYBLUE (-8000 775);
FORCEPROP 1 LAST VALUE 22UF
J 0
(-8000 875);
DISPLAY 0.489362 (-8000 875);
PAINT SKYBLUE (-8000 875);
FORCEPROP 1 LAST PART_NUMBER CH622KMEB02
J 0
(-8000 675);
DISPLAY 0.489362 (-8000 675);
PAINT SKYBLUE (-8000 675);
FORCEPROP 1 LAST VOLTAGE 4V
J 0
(-8000 825);
DISPLAY 0.489362 (-8000 825);
PAINT SKYBLUE (-8000 825);
FORCEPROP 1 LAST PACK_TYPE C0402
J 0
(-8000 625);
DISPLAY 0.489362 (-8000 625);
PAINT SKYBLUE (-8000 625);
FORCEPROP 2 LAST CDS_LIB pure_quanta
J 0
(-8050 825);
PAINT MONO (-8050 825);
DISPLAY INVISIBLE (-8050 825);
FORCEPROP 1 LAST PATH I11
J 0
(-8000 975);
DISPLAY 0.978723 (-8000 975);
PAINT WHITE (-8000 975);
DISPLAY INVISIBLE (-8000 975);
FORCEADD Q_CAP..1
(-7600 825);
FORCEPROP 1 LAST LOCATION C3902
J 0
(-7550 925);
DISPLAY 0.489362 (-7550 925);
PAINT SKYBLUE (-7550 925);
FORCEPROP 2 LAST $SEC 1
J 0
(-7550 1025);
DISPLAY 0.680851 (-7550 1025);
PAINT MONO (-7550 1025);
DISPLAY INVISIBLE (-7550 1025);
FORCEPROP 2 LAST CDS_SEC 1
J 0
(-7550 1025);
DISPLAY 1.021277 (-7550 1025);
DISPLAY INVISIBLE (-7550 1025);
FORCEPROP 1 LASTPIN (-7600 925) $PN 1
J 0
(-7590 905);
DISPLAY 0.489362 (-7590 905);
FORCEPROP 1 LASTPIN (-7600 725) $PN 2
J 0
(-7590 705);
DISPLAY 0.489362 (-7590 705);
FORCEPROP 1 LAST MATERIAL X6S
J 0
(-7550 725);
DISPLAY 0.489362 (-7550 725);
PAINT SKYBLUE (-7550 725);
FORCEPROP 1 LAST TOLERANCE 20%
J 0
(-7550 775);
DISPLAY 0.489362 (-7550 775);
PAINT SKYBLUE (-7550 775);
FORCEPROP 1 LAST VALUE 22UF
J 0
(-7550 875);
DISPLAY 0.489362 (-7550 875);
PAINT SKYBLUE (-7550 875);
FORCEPROP 1 LAST PART_NUMBER CH622KMEB02
J 0
(-7550 675);
DISPLAY 0.489362 (-7550 675);
PAINT SKYBLUE (-7550 675);
FORCEPROP 1 LAST VOLTAGE 4V
J 0
(-7550 825);
DISPLAY 0.489362 (-7550 825);
PAINT SKYBLUE (-7550 825);
FORCEPROP 1 LAST PACK_TYPE C0402
J 0
(-7550 625);
DISPLAY 0.489362 (-7550 625);
PAINT SKYBLUE (-7550 625);
FORCEPROP 2 LAST CDS_LIB pure_quanta
J 0
(-7600 825);
PAINT MONO (-7600 825);
DISPLAY INVISIBLE (-7600 825);
FORCEPROP 1 LAST PATH I12
J 0
(-7550 975);
DISPLAY 0.978723 (-7550 975);
PAINT WHITE (-7550 975);
DISPLAY INVISIBLE (-7550 975);
FORCEADD Q_CAP..1
(-8050 1575);
FORCEPROP 1 LAST LOCATION C2266
J 0
(-8000 1675);
DISPLAY 0.489362 (-8000 1675);
PAINT SKYBLUE (-8000 1675);
FORCEPROP 2 LAST $SEC 1
J 0
(-8000 1775);
DISPLAY 0.680851 (-8000 1775);
PAINT MONO (-8000 1775);
DISPLAY INVISIBLE (-8000 1775);
FORCEPROP 2 LAST CDS_SEC 1
J 0
(-8000 1775);
DISPLAY 1.021277 (-8000 1775);
DISPLAY INVISIBLE (-8000 1775);
FORCEPROP 1 LASTPIN (-8050 1675) $PN 1
J 0
(-8040 1655);
DISPLAY 0.489362 (-8040 1655);
FORCEPROP 1 LASTPIN (-8050 1475) $PN 2
J 0
(-8040 1455);
DISPLAY 0.489362 (-8040 1455);
FORCEPROP 1 LAST MATERIAL X6S
J 0
(-8000 1475);
DISPLAY 0.489362 (-8000 1475);
PAINT SKYBLUE (-8000 1475);
FORCEPROP 1 LAST TOLERANCE 20%
J 0
(-8000 1525);
DISPLAY 0.489362 (-8000 1525);
PAINT SKYBLUE (-8000 1525);
FORCEPROP 1 LAST VALUE 22UF
J 0
(-8000 1625);
DISPLAY 0.489362 (-8000 1625);
PAINT SKYBLUE (-8000 1625);
FORCEPROP 1 LAST PART_NUMBER CH622KMEB02
J 0
(-8000 1425);
DISPLAY 0.489362 (-8000 1425);
PAINT SKYBLUE (-8000 1425);
FORCEPROP 1 LAST VOLTAGE 4V
J 0
(-8000 1575);
DISPLAY 0.489362 (-8000 1575);
PAINT SKYBLUE (-8000 1575);
FORCEPROP 1 LAST PACK_TYPE C0402
J 0
(-8000 1375);
DISPLAY 0.489362 (-8000 1375);
PAINT SKYBLUE (-8000 1375);
FORCEPROP 2 LAST CDS_LIB pure_quanta
J 0
(-8050 1575);
PAINT MONO (-8050 1575);
DISPLAY INVISIBLE (-8050 1575);
FORCEPROP 1 LAST PATH I13
J 0
(-8000 1725);
DISPLAY 0.978723 (-8000 1725);
PAINT WHITE (-8000 1725);
DISPLAY INVISIBLE (-8000 1725);
FORCEADD Q_CAP..1
(-7600 1575);
FORCEPROP 1 LAST LOCATION C2271
J 0
(-7550 1675);
DISPLAY 0.489362 (-7550 1675);
PAINT SKYBLUE (-7550 1675);
FORCEPROP 2 LAST $SEC 1
J 0
(-7550 1775);
DISPLAY 0.680851 (-7550 1775);
PAINT MONO (-7550 1775);
DISPLAY INVISIBLE (-7550 1775);
FORCEPROP 2 LAST CDS_SEC 1
J 0
(-7550 1775);
DISPLAY 1.021277 (-7550 1775);
DISPLAY INVISIBLE (-7550 1775);
FORCEPROP 1 LASTPIN (-7600 1675) $PN 1
J 0
(-7590 1655);
DISPLAY 0.489362 (-7590 1655);
FORCEPROP 1 LASTPIN (-7600 1475) $PN 2
J 0
(-7590 1455);
DISPLAY 0.489362 (-7590 1455);
FORCEPROP 1 LAST MATERIAL X6S
J 0
(-7550 1475);
DISPLAY 0.489362 (-7550 1475);
PAINT SKYBLUE (-7550 1475);
FORCEPROP 1 LAST TOLERANCE 20%
J 0
(-7550 1525);
DISPLAY 0.489362 (-7550 1525);
PAINT SKYBLUE (-7550 1525);
FORCEPROP 1 LAST VALUE 22UF
J 0
(-7550 1625);
DISPLAY 0.489362 (-7550 1625);
PAINT SKYBLUE (-7550 1625);
FORCEPROP 1 LAST PART_NUMBER CH622KMEB02
J 0
(-7550 1425);
DISPLAY 0.489362 (-7550 1425);
PAINT SKYBLUE (-7550 1425);
FORCEPROP 1 LAST VOLTAGE 4V
J 0
(-7550 1575);
DISPLAY 0.489362 (-7550 1575);
PAINT SKYBLUE (-7550 1575);
FORCEPROP 1 LAST PACK_TYPE C0402
J 0
(-7550 1375);
DISPLAY 0.489362 (-7550 1375);
PAINT SKYBLUE (-7550 1375);
FORCEPROP 2 LAST CDS_LIB pure_quanta
J 0
(-7600 1575);
PAINT MONO (-7600 1575);
DISPLAY INVISIBLE (-7600 1575);
FORCEPROP 1 LAST PATH I14
J 0
(-7550 1725);
DISPLAY 0.978723 (-7550 1725);
PAINT WHITE (-7550 1725);
DISPLAY INVISIBLE (-7550 1725);
FORCEADD Q_CAP..1
(-7150 825);
FORCEPROP 1 LAST LOCATION C3903
J 0
(-7100 925);
DISPLAY 0.489362 (-7100 925);
PAINT SKYBLUE (-7100 925);
FORCEPROP 2 LAST $SEC 1
J 0
(-7100 1025);
DISPLAY 0.680851 (-7100 1025);
PAINT MONO (-7100 1025);
DISPLAY INVISIBLE (-7100 1025);
FORCEPROP 2 LAST CDS_SEC 1
J 0
(-7100 1025);
DISPLAY 1.021277 (-7100 1025);
DISPLAY INVISIBLE (-7100 1025);
FORCEPROP 1 LASTPIN (-7150 925) $PN 1
J 0
(-7140 905);
DISPLAY 0.489362 (-7140 905);
FORCEPROP 1 LASTPIN (-7150 725) $PN 2
J 0
(-7140 705);
DISPLAY 0.489362 (-7140 705);
FORCEPROP 1 LAST MATERIAL X6S
J 0
(-7100 725);
DISPLAY 0.489362 (-7100 725);
PAINT SKYBLUE (-7100 725);
FORCEPROP 1 LAST TOLERANCE 20%
J 0
(-7100 775);
DISPLAY 0.489362 (-7100 775);
PAINT SKYBLUE (-7100 775);
FORCEPROP 1 LAST VALUE 22UF
J 0
(-7100 875);
DISPLAY 0.489362 (-7100 875);
PAINT SKYBLUE (-7100 875);
FORCEPROP 1 LAST PART_NUMBER CH622KMEB02
J 0
(-7100 675);
DISPLAY 0.489362 (-7100 675);
PAINT SKYBLUE (-7100 675);
FORCEPROP 1 LAST VOLTAGE 4V
J 0
(-7100 825);
DISPLAY 0.489362 (-7100 825);
PAINT SKYBLUE (-7100 825);
FORCEPROP 1 LAST PACK_TYPE C0402
J 0
(-7100 625);
DISPLAY 0.489362 (-7100 625);
PAINT SKYBLUE (-7100 625);
FORCEPROP 2 LAST CDS_LIB pure_quanta
J 0
(-7150 825);
PAINT MONO (-7150 825);
DISPLAY INVISIBLE (-7150 825);
FORCEPROP 1 LAST PATH I15
J 0
(-7100 975);
DISPLAY 0.978723 (-7100 975);
PAINT WHITE (-7100 975);
DISPLAY INVISIBLE (-7100 975);
FORCEADD Q_CAP..1
(-6700 825);
FORCEPROP 1 LAST LOCATION C3904
J 0
(-6650 925);
DISPLAY 0.489362 (-6650 925);
PAINT SKYBLUE (-6650 925);
FORCEPROP 2 LAST $SEC 1
J 0
(-6650 1025);
DISPLAY 0.680851 (-6650 1025);
PAINT MONO (-6650 1025);
DISPLAY INVISIBLE (-6650 1025);
FORCEPROP 2 LAST CDS_SEC 1
J 0
(-6650 1025);
DISPLAY 1.021277 (-6650 1025);
DISPLAY INVISIBLE (-6650 1025);
FORCEPROP 1 LASTPIN (-6700 925) $PN 1
J 0
(-6690 905);
DISPLAY 0.489362 (-6690 905);
FORCEPROP 1 LASTPIN (-6700 725) $PN 2
J 0
(-6690 705);
DISPLAY 0.489362 (-6690 705);
FORCEPROP 1 LAST MATERIAL X6S
J 0
(-6650 725);
DISPLAY 0.489362 (-6650 725);
PAINT SKYBLUE (-6650 725);
FORCEPROP 1 LAST TOLERANCE 20%
J 0
(-6650 775);
DISPLAY 0.489362 (-6650 775);
PAINT SKYBLUE (-6650 775);
FORCEPROP 1 LAST VALUE 22UF
J 0
(-6650 875);
DISPLAY 0.489362 (-6650 875);
PAINT SKYBLUE (-6650 875);
FORCEPROP 1 LAST PART_NUMBER CH622KMEB02
J 0
(-6650 675);
DISPLAY 0.489362 (-6650 675);
PAINT SKYBLUE (-6650 675);
FORCEPROP 1 LAST VOLTAGE 4V
J 0
(-6650 825);
DISPLAY 0.489362 (-6650 825);
PAINT SKYBLUE (-6650 825);
FORCEPROP 1 LAST PACK_TYPE C0402
J 0
(-6650 625);
DISPLAY 0.489362 (-6650 625);
PAINT SKYBLUE (-6650 625);
FORCEPROP 2 LAST CDS_LIB pure_quanta
J 0
(-6700 825);
PAINT MONO (-6700 825);
DISPLAY INVISIBLE (-6700 825);
FORCEPROP 1 LAST PATH I16
J 0
(-6650 975);
DISPLAY 0.978723 (-6650 975);
PAINT WHITE (-6650 975);
DISPLAY INVISIBLE (-6650 975);
FORCEADD UNIVERSAL_GND..1
(-6250 450);
FORCEPROP 3 LASTPIN (-6250 500) SIG_NAME GND\g
J 0
(-6240 510);
DISPLAY 0.659574 (-6240 510);
PAINT MONO (-6240 510);
DISPLAY INVISIBLE (-6240 510);
FORCEPROP 2 LAST CDS_LIB pure_quanta_power
J 0
(-6250 450);
PAINT MONO (-6250 450);
DISPLAY INVISIBLE (-6250 450);
FORCEPROP 1 LAST PATH I17
J 0
(-6175 450);
DISPLAY 0.872340 (-6175 450);
PAINT AQUA (-6175 450);
DISPLAY INVISIBLE (-6175 450);
FORCEPROP 1 LAST HDL_POWER GND
J 1
(-6225 375);
DISPLAY 0.872340 (-6225 375);
PAINT GREEN (-6225 375);
DISPLAY INVISIBLE (-6225 375);
FORCEADD Q_CAP..1
(-6250 825);
FORCEPROP 1 LAST LOCATION C3905
J 0
(-6200 925);
DISPLAY 0.489362 (-6200 925);
PAINT SKYBLUE (-6200 925);
FORCEPROP 2 LAST $SEC 1
J 0
(-6200 1025);
DISPLAY 0.680851 (-6200 1025);
PAINT MONO (-6200 1025);
DISPLAY INVISIBLE (-6200 1025);
FORCEPROP 2 LAST CDS_SEC 1
J 0
(-6200 1025);
DISPLAY 1.021277 (-6200 1025);
DISPLAY INVISIBLE (-6200 1025);
FORCEPROP 1 LASTPIN (-6250 925) $PN 1
J 0
(-6240 905);
DISPLAY 0.489362 (-6240 905);
FORCEPROP 1 LASTPIN (-6250 725) $PN 2
J 0
(-6240 705);
DISPLAY 0.489362 (-6240 705);
FORCEPROP 1 LAST MATERIAL X6S
J 0
(-6200 725);
DISPLAY 0.489362 (-6200 725);
PAINT SKYBLUE (-6200 725);
FORCEPROP 1 LAST TOLERANCE 20%
J 0
(-6200 775);
DISPLAY 0.489362 (-6200 775);
PAINT SKYBLUE (-6200 775);
FORCEPROP 1 LAST VALUE 22UF
J 0
(-6200 875);
DISPLAY 0.489362 (-6200 875);
PAINT SKYBLUE (-6200 875);
FORCEPROP 1 LAST PART_NUMBER CH622KMEB02
J 0
(-6200 675);
DISPLAY 0.489362 (-6200 675);
PAINT SKYBLUE (-6200 675);
FORCEPROP 1 LAST VOLTAGE 4V
J 0
(-6200 825);
DISPLAY 0.489362 (-6200 825);
PAINT SKYBLUE (-6200 825);
FORCEPROP 1 LAST PACK_TYPE C0402
J 0
(-6200 625);
DISPLAY 0.489362 (-6200 625);
PAINT SKYBLUE (-6200 625);
FORCEPROP 2 LAST CDS_LIB pure_quanta
J 0
(-6250 825);
PAINT MONO (-6250 825);
DISPLAY INVISIBLE (-6250 825);
FORCEPROP 1 LAST PATH I18
J 0
(-6200 975);
DISPLAY 0.978723 (-6200 975);
PAINT WHITE (-6200 975);
DISPLAY INVISIBLE (-6200 975);
FORCEADD Q_CAP..1
(-7150 1575);
FORCEPROP 1 LAST LOCATION C2275
J 0
(-7100 1675);
DISPLAY 0.489362 (-7100 1675);
PAINT SKYBLUE (-7100 1675);
FORCEPROP 2 LAST $SEC 1
J 0
(-7100 1775);
DISPLAY 0.680851 (-7100 1775);
PAINT MONO (-7100 1775);
DISPLAY INVISIBLE (-7100 1775);
FORCEPROP 2 LAST CDS_SEC 1
J 0
(-7100 1775);
DISPLAY 1.021277 (-7100 1775);
DISPLAY INVISIBLE (-7100 1775);
FORCEPROP 1 LASTPIN (-7150 1675) $PN 1
J 0
(-7140 1655);
DISPLAY 0.489362 (-7140 1655);
FORCEPROP 1 LASTPIN (-7150 1475) $PN 2
J 0
(-7140 1455);
DISPLAY 0.489362 (-7140 1455);
FORCEPROP 1 LAST MATERIAL X6S
J 0
(-7100 1475);
DISPLAY 0.489362 (-7100 1475);
PAINT SKYBLUE (-7100 1475);
FORCEPROP 1 LAST TOLERANCE 20%
J 0
(-7100 1525);
DISPLAY 0.489362 (-7100 1525);
PAINT SKYBLUE (-7100 1525);
FORCEPROP 1 LAST VALUE 22UF
J 0
(-7100 1625);
DISPLAY 0.489362 (-7100 1625);
PAINT SKYBLUE (-7100 1625);
FORCEPROP 1 LAST PART_NUMBER CH622KMEB02
J 0
(-7100 1425);
DISPLAY 0.489362 (-7100 1425);
PAINT SKYBLUE (-7100 1425);
FORCEPROP 1 LAST VOLTAGE 4V
J 0
(-7100 1575);
DISPLAY 0.489362 (-7100 1575);
PAINT SKYBLUE (-7100 1575);
FORCEPROP 1 LAST PACK_TYPE C0402
J 0
(-7100 1375);
DISPLAY 0.489362 (-7100 1375);
PAINT SKYBLUE (-7100 1375);
FORCEPROP 2 LAST CDS_LIB pure_quanta
J 0
(-7150 1575);
PAINT MONO (-7150 1575);
DISPLAY INVISIBLE (-7150 1575);
FORCEPROP 1 LAST PATH I19
J 0
(-7100 1725);
DISPLAY 0.978723 (-7100 1725);
PAINT WHITE (-7100 1725);
DISPLAY INVISIBLE (-7100 1725);
FORCEADD UNIVERSAL_POWER..1
(-8500 1100);
FORCEPROP 3 LASTPIN (-8500 1050) SIG_NAME PVDD11_S3_P1\g
J 0
(-8490 1060);
DISPLAY 0.659574 (-8490 1060);
PAINT MONO (-8490 1060);
DISPLAY INVISIBLE (-8490 1060);
FORCEPROP 1 LAST HDL_POWER PVDD11_S3_P1
J 1
(-8500 1150);
DISPLAY 0.489362 (-8500 1150);
PAINT GREEN (-8500 1150);
FORCEPROP 2 LAST CDS_LIB pure_quanta_power
J 0
(-8500 1100);
DISPLAY INVISIBLE (-8500 1100);
FORCEPROP 1 LAST PATH I2
J 0
(-8450 1125);
DISPLAY 0.872340 (-8450 1125);
PAINT AQUA (-8450 1125);
DISPLAY INVISIBLE (-8450 1125);
FORCEADD Q_CAP..1
(-6700 1575);
FORCEPROP 1 LAST LOCATION C2279
J 0
(-6650 1675);
DISPLAY 0.489362 (-6650 1675);
PAINT SKYBLUE (-6650 1675);
FORCEPROP 2 LAST $SEC 1
J 0
(-6650 1775);
DISPLAY 0.680851 (-6650 1775);
PAINT MONO (-6650 1775);
DISPLAY INVISIBLE (-6650 1775);
FORCEPROP 2 LAST CDS_SEC 1
J 0
(-6650 1775);
DISPLAY 1.021277 (-6650 1775);
DISPLAY INVISIBLE (-6650 1775);
FORCEPROP 1 LASTPIN (-6700 1675) $PN 1
J 0
(-6690 1655);
DISPLAY 0.489362 (-6690 1655);
FORCEPROP 1 LASTPIN (-6700 1475) $PN 2
J 0
(-6690 1455);
DISPLAY 0.489362 (-6690 1455);
FORCEPROP 1 LAST MATERIAL X6S
J 0
(-6650 1475);
DISPLAY 0.489362 (-6650 1475);
PAINT SKYBLUE (-6650 1475);
FORCEPROP 1 LAST TOLERANCE 20%
J 0
(-6650 1525);
DISPLAY 0.489362 (-6650 1525);
PAINT SKYBLUE (-6650 1525);
FORCEPROP 1 LAST VALUE 22UF
J 0
(-6650 1625);
DISPLAY 0.489362 (-6650 1625);
PAINT SKYBLUE (-6650 1625);
FORCEPROP 1 LAST PART_NUMBER CH622KMEB02
J 0
(-6650 1425);
DISPLAY 0.489362 (-6650 1425);
PAINT SKYBLUE (-6650 1425);
FORCEPROP 1 LAST VOLTAGE 4V
J 0
(-6650 1575);
DISPLAY 0.489362 (-6650 1575);
PAINT SKYBLUE (-6650 1575);
FORCEPROP 1 LAST PACK_TYPE C0402
J 0
(-6650 1375);
DISPLAY 0.489362 (-6650 1375);
PAINT SKYBLUE (-6650 1375);
FORCEPROP 2 LAST CDS_LIB pure_quanta
J 0
(-6700 1575);
PAINT MONO (-6700 1575);
DISPLAY INVISIBLE (-6700 1575);
FORCEPROP 1 LAST PATH I20
J 0
(-6650 1725);
DISPLAY 0.978723 (-6650 1725);
PAINT WHITE (-6650 1725);
DISPLAY INVISIBLE (-6650 1725);
FORCEADD Q_CAP..1
(-6250 1575);
FORCEPROP 1 LAST LOCATION C2282
J 0
(-6200 1675);
DISPLAY 0.489362 (-6200 1675);
PAINT SKYBLUE (-6200 1675);
FORCEPROP 2 LAST $SEC 1
J 0
(-6200 1775);
DISPLAY 0.680851 (-6200 1775);
PAINT MONO (-6200 1775);
DISPLAY INVISIBLE (-6200 1775);
FORCEPROP 2 LAST CDS_SEC 1
J 0
(-6200 1775);
DISPLAY 1.021277 (-6200 1775);
DISPLAY INVISIBLE (-6200 1775);
FORCEPROP 1 LASTPIN (-6250 1675) $PN 1
J 0
(-6240 1655);
DISPLAY 0.489362 (-6240 1655);
FORCEPROP 1 LASTPIN (-6250 1475) $PN 2
J 0
(-6240 1455);
DISPLAY 0.489362 (-6240 1455);
FORCEPROP 1 LAST MATERIAL X6S
J 0
(-6200 1475);
DISPLAY 0.489362 (-6200 1475);
PAINT SKYBLUE (-6200 1475);
FORCEPROP 1 LAST TOLERANCE 20%
J 0
(-6200 1525);
DISPLAY 0.489362 (-6200 1525);
PAINT SKYBLUE (-6200 1525);
FORCEPROP 1 LAST VALUE 22UF
J 0
(-6200 1625);
DISPLAY 0.489362 (-6200 1625);
PAINT SKYBLUE (-6200 1625);
FORCEPROP 1 LAST PART_NUMBER CH622KMEB02
J 0
(-6200 1425);
DISPLAY 0.489362 (-6200 1425);
PAINT SKYBLUE (-6200 1425);
FORCEPROP 1 LAST VOLTAGE 4V
J 0
(-6200 1575);
DISPLAY 0.489362 (-6200 1575);
PAINT SKYBLUE (-6200 1575);
FORCEPROP 1 LAST PACK_TYPE C0402
J 0
(-6200 1375);
DISPLAY 0.489362 (-6200 1375);
PAINT SKYBLUE (-6200 1375);
FORCEPROP 2 LAST CDS_LIB pure_quanta
J 0
(-6250 1575);
PAINT MONO (-6250 1575);
DISPLAY INVISIBLE (-6250 1575);
FORCEPROP 1 LAST PATH I21
J 0
(-6200 1725);
DISPLAY 0.978723 (-6200 1725);
PAINT WHITE (-6200 1725);
DISPLAY INVISIBLE (-6200 1725);
FORCEADD UNIVERSAL_GND..1
(-8075 3025);
FORCEPROP 3 LASTPIN (-8075 3075) SIG_NAME GND\g
J 0
(-8065 3085);
DISPLAY 0.659574 (-8065 3085);
PAINT MONO (-8065 3085);
DISPLAY INVISIBLE (-8065 3085);
FORCEPROP 2 LAST CDS_LIB pure_quanta_power
J 0
(-8075 3025);
DISPLAY INVISIBLE (-8075 3025);
FORCEPROP 1 LAST PATH I22
J 0
(-8000 3025);
DISPLAY 0.872340 (-8000 3025);
PAINT AQUA (-8000 3025);
DISPLAY INVISIBLE (-8000 3025);
FORCEPROP 1 LAST HDL_POWER GND
J 1
(-8050 2950);
DISPLAY 0.872340 (-8050 2950);
PAINT GREEN (-8050 2950);
DISPLAY INVISIBLE (-8050 2950);
FORCEADD Q_CAP..1
(-8075 3375);
FORCEPROP 1 LAST LOCATION C3901
J 0
(-8025 3475);
DISPLAY 0.489362 (-8025 3475);
PAINT SKYBLUE (-8025 3475);
FORCEPROP 2 LAST $SEC 1
J 0
(-8025 3575);
DISPLAY 0.680851 (-8025 3575);
PAINT MONO (-8025 3575);
DISPLAY INVISIBLE (-8025 3575);
FORCEPROP 2 LAST CDS_SEC 1
J 0
(-8025 3575);
DISPLAY 1.021277 (-8025 3575);
DISPLAY INVISIBLE (-8025 3575);
FORCEPROP 1 LASTPIN (-8075 3475) $PN 1
J 0
(-8065 3455);
DISPLAY 0.489362 (-8065 3455);
FORCEPROP 1 LASTPIN (-8075 3275) $PN 2
J 0
(-8065 3255);
DISPLAY 0.489362 (-8065 3255);
FORCEPROP 1 LAST MATERIAL X6S
J 0
(-8025 3275);
DISPLAY 0.489362 (-8025 3275);
PAINT SKYBLUE (-8025 3275);
FORCEPROP 1 LAST TOLERANCE 20%
J 0
(-8025 3325);
DISPLAY 0.489362 (-8025 3325);
PAINT SKYBLUE (-8025 3325);
FORCEPROP 1 LAST VALUE 22UF
J 0
(-8025 3425);
DISPLAY 0.489362 (-8025 3425);
PAINT SKYBLUE (-8025 3425);
FORCEPROP 1 LAST PART_NUMBER CH622KMEB02
J 0
(-8025 3225);
DISPLAY 0.489362 (-8025 3225);
PAINT SKYBLUE (-8025 3225);
FORCEPROP 1 LAST VOLTAGE 4V
J 0
(-8025 3375);
DISPLAY 0.489362 (-8025 3375);
PAINT SKYBLUE (-8025 3375);
FORCEPROP 1 LAST PACK_TYPE C0402
J 0
(-8025 3175);
DISPLAY 0.489362 (-8025 3175);
PAINT SKYBLUE (-8025 3175);
FORCEPROP 2 LAST CDS_LIB pure_quanta
J 0
(-8075 3375);
PAINT MONO (-8075 3375);
DISPLAY INVISIBLE (-8075 3375);
FORCEPROP 1 LAST PATH I23
J 0
(-8025 3525);
DISPLAY 0.978723 (-8025 3525);
PAINT WHITE (-8025 3525);
DISPLAY INVISIBLE (-8025 3525);
FORCEADD Q_CAP..1
(-5800 1575);
FORCEPROP 1 LAST LOCATION C2285
J 0
(-5750 1675);
DISPLAY 0.489362 (-5750 1675);
PAINT SKYBLUE (-5750 1675);
FORCEPROP 2 LAST $SEC 1
J 0
(-5750 1775);
DISPLAY 0.680851 (-5750 1775);
PAINT MONO (-5750 1775);
DISPLAY INVISIBLE (-5750 1775);
FORCEPROP 2 LAST CDS_SEC 1
J 0
(-5750 1775);
DISPLAY 1.021277 (-5750 1775);
DISPLAY INVISIBLE (-5750 1775);
FORCEPROP 1 LASTPIN (-5800 1675) $PN 1
J 0
(-5790 1655);
DISPLAY 0.489362 (-5790 1655);
FORCEPROP 1 LASTPIN (-5800 1475) $PN 2
J 0
(-5790 1455);
DISPLAY 0.489362 (-5790 1455);
FORCEPROP 1 LAST MATERIAL X6S
J 0
(-5750 1475);
DISPLAY 0.489362 (-5750 1475);
PAINT SKYBLUE (-5750 1475);
FORCEPROP 1 LAST TOLERANCE 20%
J 0
(-5750 1525);
DISPLAY 0.489362 (-5750 1525);
PAINT SKYBLUE (-5750 1525);
FORCEPROP 1 LAST VALUE 22UF
J 0
(-5750 1625);
DISPLAY 0.489362 (-5750 1625);
PAINT SKYBLUE (-5750 1625);
FORCEPROP 1 LAST PART_NUMBER CH622KMEB02
J 0
(-5750 1425);
DISPLAY 0.489362 (-5750 1425);
PAINT SKYBLUE (-5750 1425);
FORCEPROP 1 LAST VOLTAGE 4V
J 0
(-5750 1575);
DISPLAY 0.489362 (-5750 1575);
PAINT SKYBLUE (-5750 1575);
FORCEPROP 1 LAST PACK_TYPE C0402
J 0
(-5750 1375);
DISPLAY 0.489362 (-5750 1375);
PAINT SKYBLUE (-5750 1375);
FORCEPROP 2 LAST CDS_LIB pure_quanta
J 0
(-5800 1575);
PAINT MONO (-5800 1575);
DISPLAY INVISIBLE (-5800 1575);
FORCEPROP 1 LAST PATH I24
J 0
(-5750 1725);
DISPLAY 0.978723 (-5750 1725);
PAINT WHITE (-5750 1725);
DISPLAY INVISIBLE (-5750 1725);
FORCEADD Q_CAP..1
(-5350 1575);
FORCEPROP 1 LAST LOCATION C2287
J 0
(-5300 1675);
DISPLAY 0.489362 (-5300 1675);
PAINT SKYBLUE (-5300 1675);
FORCEPROP 2 LAST $SEC 1
J 0
(-5300 1775);
DISPLAY 0.680851 (-5300 1775);
PAINT MONO (-5300 1775);
DISPLAY INVISIBLE (-5300 1775);
FORCEPROP 2 LAST CDS_SEC 1
J 0
(-5300 1775);
DISPLAY 1.021277 (-5300 1775);
DISPLAY INVISIBLE (-5300 1775);
FORCEPROP 1 LASTPIN (-5350 1675) $PN 1
J 0
(-5340 1655);
DISPLAY 0.489362 (-5340 1655);
FORCEPROP 1 LASTPIN (-5350 1475) $PN 2
J 0
(-5340 1455);
DISPLAY 0.489362 (-5340 1455);
FORCEPROP 1 LAST MATERIAL X6S
J 0
(-5300 1475);
DISPLAY 0.489362 (-5300 1475);
PAINT SKYBLUE (-5300 1475);
FORCEPROP 1 LAST TOLERANCE 20%
J 0
(-5300 1525);
DISPLAY 0.489362 (-5300 1525);
PAINT SKYBLUE (-5300 1525);
FORCEPROP 1 LAST VALUE 22UF
J 0
(-5300 1625);
DISPLAY 0.489362 (-5300 1625);
PAINT SKYBLUE (-5300 1625);
FORCEPROP 1 LAST PART_NUMBER CH622KMEB02
J 0
(-5300 1425);
DISPLAY 0.489362 (-5300 1425);
PAINT SKYBLUE (-5300 1425);
FORCEPROP 1 LAST VOLTAGE 4V
J 0
(-5300 1575);
DISPLAY 0.489362 (-5300 1575);
PAINT SKYBLUE (-5300 1575);
FORCEPROP 1 LAST PACK_TYPE C0402
J 0
(-5300 1375);
DISPLAY 0.489362 (-5300 1375);
PAINT SKYBLUE (-5300 1375);
FORCEPROP 2 LAST CDS_LIB pure_quanta
J 0
(-5350 1575);
PAINT MONO (-5350 1575);
DISPLAY INVISIBLE (-5350 1575);
FORCEPROP 1 LAST PATH I25
J 0
(-5300 1725);
DISPLAY 0.978723 (-5300 1725);
PAINT WHITE (-5300 1725);
DISPLAY INVISIBLE (-5300 1725);
FORCEADD Q_CAP..1
(-4900 1575);
FORCEPROP 1 LAST LOCATION C2289
J 0
(-4850 1675);
DISPLAY 0.489362 (-4850 1675);
PAINT SKYBLUE (-4850 1675);
FORCEPROP 2 LAST $SEC 1
J 0
(-4850 1775);
DISPLAY 0.680851 (-4850 1775);
PAINT MONO (-4850 1775);
DISPLAY INVISIBLE (-4850 1775);
FORCEPROP 2 LAST CDS_SEC 1
J 0
(-4850 1775);
DISPLAY 1.021277 (-4850 1775);
DISPLAY INVISIBLE (-4850 1775);
FORCEPROP 1 LASTPIN (-4900 1675) $PN 1
J 0
(-4890 1655);
DISPLAY 0.489362 (-4890 1655);
FORCEPROP 1 LASTPIN (-4900 1475) $PN 2
J 0
(-4890 1455);
DISPLAY 0.489362 (-4890 1455);
FORCEPROP 1 LAST MATERIAL X6S
J 0
(-4850 1475);
DISPLAY 0.489362 (-4850 1475);
PAINT SKYBLUE (-4850 1475);
FORCEPROP 1 LAST TOLERANCE 20%
J 0
(-4850 1525);
DISPLAY 0.489362 (-4850 1525);
PAINT SKYBLUE (-4850 1525);
FORCEPROP 1 LAST VALUE 22UF
J 0
(-4850 1625);
DISPLAY 0.489362 (-4850 1625);
PAINT SKYBLUE (-4850 1625);
FORCEPROP 1 LAST PART_NUMBER CH622KMEB02
J 0
(-4850 1425);
DISPLAY 0.489362 (-4850 1425);
PAINT SKYBLUE (-4850 1425);
FORCEPROP 1 LAST VOLTAGE 4V
J 0
(-4850 1575);
DISPLAY 0.489362 (-4850 1575);
PAINT SKYBLUE (-4850 1575);
FORCEPROP 1 LAST PACK_TYPE C0402
J 0
(-4850 1375);
DISPLAY 0.489362 (-4850 1375);
PAINT SKYBLUE (-4850 1375);
FORCEPROP 2 LAST CDS_LIB pure_quanta
J 0
(-4900 1575);
PAINT MONO (-4900 1575);
DISPLAY INVISIBLE (-4900 1575);
FORCEPROP 1 LAST PATH I26
J 0
(-4850 1725);
DISPLAY 0.978723 (-4850 1725);
PAINT WHITE (-4850 1725);
DISPLAY INVISIBLE (-4850 1725);
FORCEADD UNIVERSAL_GND..1
(-4500 1200);
FORCEPROP 3 LASTPIN (-4500 1250) SIG_NAME GND\g
J 0
(-4490 1260);
DISPLAY 0.659574 (-4490 1260);
PAINT MONO (-4490 1260);
DISPLAY INVISIBLE (-4490 1260);
FORCEPROP 2 LAST CDS_LIB pure_quanta_power
J 0
(-4500 1200);
PAINT MONO (-4500 1200);
DISPLAY INVISIBLE (-4500 1200);
FORCEPROP 1 LAST PATH I27
J 0
(-4425 1200);
DISPLAY 0.872340 (-4425 1200);
PAINT AQUA (-4425 1200);
DISPLAY INVISIBLE (-4425 1200);
FORCEPROP 1 LAST HDL_POWER GND
J 1
(-4475 1125);
DISPLAY 0.872340 (-4475 1125);
PAINT GREEN (-4475 1125);
DISPLAY INVISIBLE (-4475 1125);
FORCEADD Q_CAP..1
(-4500 1575);
FORCEPROP 1 LAST LOCATION C2291
J 0
(-4450 1675);
DISPLAY 0.489362 (-4450 1675);
PAINT SKYBLUE (-4450 1675);
FORCEPROP 2 LAST $SEC 1
J 0
(-4450 1775);
DISPLAY 0.680851 (-4450 1775);
PAINT MONO (-4450 1775);
DISPLAY INVISIBLE (-4450 1775);
FORCEPROP 2 LAST CDS_SEC 1
J 0
(-4450 1775);
DISPLAY 1.021277 (-4450 1775);
DISPLAY INVISIBLE (-4450 1775);
FORCEPROP 1 LASTPIN (-4500 1675) $PN 1
J 0
(-4490 1655);
DISPLAY 0.489362 (-4490 1655);
FORCEPROP 1 LASTPIN (-4500 1475) $PN 2
J 0
(-4490 1455);
DISPLAY 0.489362 (-4490 1455);
FORCEPROP 1 LAST MATERIAL X6S
J 0
(-4450 1475);
DISPLAY 0.489362 (-4450 1475);
PAINT SKYBLUE (-4450 1475);
FORCEPROP 1 LAST TOLERANCE 20%
J 0
(-4450 1525);
DISPLAY 0.489362 (-4450 1525);
PAINT SKYBLUE (-4450 1525);
FORCEPROP 1 LAST VALUE 22UF
J 0
(-4450 1625);
DISPLAY 0.489362 (-4450 1625);
PAINT SKYBLUE (-4450 1625);
FORCEPROP 1 LAST PART_NUMBER CH622KMEB02
J 0
(-4450 1425);
DISPLAY 0.489362 (-4450 1425);
PAINT SKYBLUE (-4450 1425);
FORCEPROP 1 LAST VOLTAGE 4V
J 0
(-4450 1575);
DISPLAY 0.489362 (-4450 1575);
PAINT SKYBLUE (-4450 1575);
FORCEPROP 1 LAST PACK_TYPE C0402
J 0
(-4450 1375);
DISPLAY 0.489362 (-4450 1375);
PAINT SKYBLUE (-4450 1375);
FORCEPROP 2 LAST CDS_LIB pure_quanta
J 0
(-4500 1575);
PAINT MONO (-4500 1575);
DISPLAY INVISIBLE (-4500 1575);
FORCEPROP 1 LAST PATH I28
J 0
(-4450 1725);
DISPLAY 0.978723 (-4450 1725);
PAINT WHITE (-4450 1725);
DISPLAY INVISIBLE (-4450 1725);
FORCEADD UNIVERSAL_GND..1
(-4525 3725);
FORCEPROP 3 LASTPIN (-4525 3775) SIG_NAME GND\g
J 0
(-4515 3785);
DISPLAY 0.659574 (-4515 3785);
PAINT MONO (-4515 3785);
DISPLAY INVISIBLE (-4515 3785);
FORCEPROP 2 LAST CDS_LIB pure_quanta_power
J 0
(-4525 3725);
PAINT MONO (-4525 3725);
DISPLAY INVISIBLE (-4525 3725);
FORCEPROP 1 LAST PATH I29
J 0
(-4450 3725);
DISPLAY 0.872340 (-4450 3725);
PAINT AQUA (-4450 3725);
DISPLAY INVISIBLE (-4450 3725);
FORCEPROP 1 LAST HDL_POWER GND
J 1
(-4500 3650);
DISPLAY 0.872340 (-4500 3650);
PAINT GREEN (-4500 3650);
DISPLAY INVISIBLE (-4500 3650);
FORCEADD Q_CAP..1
(-8500 1575);
FORCEPROP 1 LAST LOCATION C2261
J 0
(-8450 1675);
DISPLAY 0.489362 (-8450 1675);
PAINT SKYBLUE (-8450 1675);
FORCEPROP 2 LAST $SEC 1
J 0
(-8450 1775);
DISPLAY 0.680851 (-8450 1775);
PAINT MONO (-8450 1775);
DISPLAY INVISIBLE (-8450 1775);
FORCEPROP 2 LAST CDS_SEC 1
J 0
(-8450 1775);
DISPLAY 1.021277 (-8450 1775);
DISPLAY INVISIBLE (-8450 1775);
FORCEPROP 1 LASTPIN (-8500 1675) $PN 1
J 0
(-8490 1655);
DISPLAY 0.489362 (-8490 1655);
FORCEPROP 1 LASTPIN (-8500 1475) $PN 2
J 0
(-8490 1455);
DISPLAY 0.489362 (-8490 1455);
FORCEPROP 1 LAST MATERIAL X6S
J 0
(-8450 1475);
DISPLAY 0.489362 (-8450 1475);
PAINT SKYBLUE (-8450 1475);
FORCEPROP 1 LAST TOLERANCE 20%
J 0
(-8450 1525);
DISPLAY 0.489362 (-8450 1525);
PAINT SKYBLUE (-8450 1525);
FORCEPROP 1 LAST VALUE 22UF
J 0
(-8450 1625);
DISPLAY 0.489362 (-8450 1625);
PAINT SKYBLUE (-8450 1625);
FORCEPROP 1 LAST PART_NUMBER CH622KMEB02
J 0
(-8450 1425);
DISPLAY 0.489362 (-8450 1425);
PAINT SKYBLUE (-8450 1425);
FORCEPROP 1 LAST VOLTAGE 4V
J 0
(-8450 1575);
DISPLAY 0.489362 (-8450 1575);
PAINT SKYBLUE (-8450 1575);
FORCEPROP 1 LAST PACK_TYPE C0402
J 0
(-8450 1375);
DISPLAY 0.489362 (-8450 1375);
PAINT SKYBLUE (-8450 1375);
FORCEPROP 2 LAST CDS_LIB pure_quanta
J 0
(-8500 1575);
PAINT MONO (-8500 1575);
DISPLAY INVISIBLE (-8500 1575);
FORCEPROP 1 LAST PATH I3
J 0
(-8450 1725);
DISPLAY 0.978723 (-8450 1725);
PAINT WHITE (-8450 1725);
DISPLAY INVISIBLE (-8450 1725);
FORCEADD Q_CAP..1
(-8075 4100);
FORCEPROP 1 LAST LOCATION C2264
J 0
(-8025 4200);
DISPLAY 0.489362 (-8025 4200);
PAINT SKYBLUE (-8025 4200);
FORCEPROP 2 LAST $SEC 1
J 0
(-8025 4300);
DISPLAY 0.680851 (-8025 4300);
PAINT MONO (-8025 4300);
DISPLAY INVISIBLE (-8025 4300);
FORCEPROP 2 LAST CDS_SEC 1
J 0
(-8025 4300);
DISPLAY 1.021277 (-8025 4300);
DISPLAY INVISIBLE (-8025 4300);
FORCEPROP 1 LASTPIN (-8075 4200) $PN 1
J 0
(-8065 4180);
DISPLAY 0.489362 (-8065 4180);
FORCEPROP 1 LASTPIN (-8075 4000) $PN 2
J 0
(-8065 3980);
DISPLAY 0.489362 (-8065 3980);
FORCEPROP 1 LAST MATERIAL X6S
J 0
(-8025 4000);
DISPLAY 0.489362 (-8025 4000);
PAINT SKYBLUE (-8025 4000);
FORCEPROP 1 LAST TOLERANCE 20%
J 0
(-8025 4050);
DISPLAY 0.489362 (-8025 4050);
PAINT SKYBLUE (-8025 4050);
FORCEPROP 1 LAST VALUE 22UF
J 0
(-8025 4150);
DISPLAY 0.489362 (-8025 4150);
PAINT SKYBLUE (-8025 4150);
FORCEPROP 1 LAST PART_NUMBER CH622KMEB02
J 0
(-8025 3950);
DISPLAY 0.489362 (-8025 3950);
PAINT SKYBLUE (-8025 3950);
FORCEPROP 1 LAST VOLTAGE 4V
J 0
(-8025 4100);
DISPLAY 0.489362 (-8025 4100);
PAINT SKYBLUE (-8025 4100);
FORCEPROP 1 LAST PACK_TYPE C0402
J 0
(-8025 3900);
DISPLAY 0.489362 (-8025 3900);
PAINT SKYBLUE (-8025 3900);
FORCEPROP 2 LAST CDS_LIB pure_quanta
J 0
(-8075 4100);
PAINT MONO (-8075 4100);
DISPLAY INVISIBLE (-8075 4100);
FORCEPROP 1 LAST PATH I30
J 0
(-8025 4250);
DISPLAY 0.978723 (-8025 4250);
PAINT WHITE (-8025 4250);
DISPLAY INVISIBLE (-8025 4250);
FORCEADD Q_CAP..1
(-8075 4900);
FORCEPROP 1 LAST LOCATION C2263
J 0
(-8025 5000);
DISPLAY 0.489362 (-8025 5000);
PAINT SKYBLUE (-8025 5000);
FORCEPROP 2 LAST $SEC 1
J 0
(-8025 5100);
DISPLAY 0.680851 (-8025 5100);
PAINT MONO (-8025 5100);
DISPLAY INVISIBLE (-8025 5100);
FORCEPROP 2 LAST CDS_SEC 1
J 0
(-8025 5100);
DISPLAY 1.021277 (-8025 5100);
DISPLAY INVISIBLE (-8025 5100);
FORCEPROP 1 LASTPIN (-8075 5000) $PN 1
J 0
(-8065 4980);
DISPLAY 0.489362 (-8065 4980);
FORCEPROP 1 LASTPIN (-8075 4800) $PN 2
J 0
(-8065 4780);
DISPLAY 0.489362 (-8065 4780);
FORCEPROP 1 LAST MATERIAL X6S
J 0
(-8025 4800);
DISPLAY 0.489362 (-8025 4800);
PAINT SKYBLUE (-8025 4800);
FORCEPROP 1 LAST TOLERANCE 20%
J 0
(-8025 4850);
DISPLAY 0.489362 (-8025 4850);
PAINT SKYBLUE (-8025 4850);
FORCEPROP 1 LAST VALUE 22UF
J 0
(-8025 4950);
DISPLAY 0.489362 (-8025 4950);
PAINT SKYBLUE (-8025 4950);
FORCEPROP 1 LAST PART_NUMBER CH622KMEB02
J 0
(-8025 4750);
DISPLAY 0.489362 (-8025 4750);
PAINT SKYBLUE (-8025 4750);
FORCEPROP 1 LAST VOLTAGE 4V
J 0
(-8025 4900);
DISPLAY 0.489362 (-8025 4900);
PAINT SKYBLUE (-8025 4900);
FORCEPROP 1 LAST PACK_TYPE C0402
J 0
(-8025 4700);
DISPLAY 0.489362 (-8025 4700);
PAINT SKYBLUE (-8025 4700);
FORCEPROP 2 LAST CDS_LIB pure_quanta
J 0
(-8075 4900);
PAINT MONO (-8075 4900);
DISPLAY INVISIBLE (-8075 4900);
FORCEPROP 1 LAST PATH I31
J 0
(-8025 5050);
DISPLAY 0.978723 (-8025 5050);
PAINT WHITE (-8025 5050);
DISPLAY INVISIBLE (-8025 5050);
FORCEADD Q_CAP..1
(-7625 4100);
FORCEPROP 1 LAST LOCATION C2269
J 0
(-7575 4200);
DISPLAY 0.489362 (-7575 4200);
PAINT SKYBLUE (-7575 4200);
FORCEPROP 2 LAST $SEC 1
J 0
(-7575 4300);
DISPLAY 0.680851 (-7575 4300);
PAINT MONO (-7575 4300);
DISPLAY INVISIBLE (-7575 4300);
FORCEPROP 2 LAST CDS_SEC 1
J 0
(-7575 4300);
DISPLAY 1.021277 (-7575 4300);
DISPLAY INVISIBLE (-7575 4300);
FORCEPROP 1 LASTPIN (-7625 4200) $PN 1
J 0
(-7615 4180);
DISPLAY 0.489362 (-7615 4180);
FORCEPROP 1 LASTPIN (-7625 4000) $PN 2
J 0
(-7615 3980);
DISPLAY 0.489362 (-7615 3980);
FORCEPROP 1 LAST MATERIAL X6S
J 0
(-7575 4000);
DISPLAY 0.489362 (-7575 4000);
PAINT SKYBLUE (-7575 4000);
FORCEPROP 1 LAST TOLERANCE 20%
J 0
(-7575 4050);
DISPLAY 0.489362 (-7575 4050);
PAINT SKYBLUE (-7575 4050);
FORCEPROP 1 LAST VALUE 22UF
J 0
(-7575 4150);
DISPLAY 0.489362 (-7575 4150);
PAINT SKYBLUE (-7575 4150);
FORCEPROP 1 LAST PART_NUMBER CH622KMEB02
J 0
(-7575 3950);
DISPLAY 0.489362 (-7575 3950);
PAINT SKYBLUE (-7575 3950);
FORCEPROP 1 LAST VOLTAGE 4V
J 0
(-7575 4100);
DISPLAY 0.489362 (-7575 4100);
PAINT SKYBLUE (-7575 4100);
FORCEPROP 1 LAST PACK_TYPE C0402
J 0
(-7575 3900);
DISPLAY 0.489362 (-7575 3900);
PAINT SKYBLUE (-7575 3900);
FORCEPROP 2 LAST CDS_LIB pure_quanta
J 0
(-7625 4100);
PAINT MONO (-7625 4100);
DISPLAY INVISIBLE (-7625 4100);
FORCEPROP 1 LAST PATH I32
J 0
(-7575 4250);
DISPLAY 0.978723 (-7575 4250);
PAINT WHITE (-7575 4250);
DISPLAY INVISIBLE (-7575 4250);
FORCEADD Q_CAP..1
(-7625 4900);
FORCEPROP 1 LAST LOCATION C2268
J 0
(-7575 5000);
DISPLAY 0.489362 (-7575 5000);
PAINT SKYBLUE (-7575 5000);
FORCEPROP 2 LAST $SEC 1
J 0
(-7575 5100);
DISPLAY 0.680851 (-7575 5100);
PAINT MONO (-7575 5100);
DISPLAY INVISIBLE (-7575 5100);
FORCEPROP 2 LAST CDS_SEC 1
J 0
(-7575 5100);
DISPLAY 1.021277 (-7575 5100);
DISPLAY INVISIBLE (-7575 5100);
FORCEPROP 1 LASTPIN (-7625 5000) $PN 1
J 0
(-7615 4980);
DISPLAY 0.489362 (-7615 4980);
FORCEPROP 1 LASTPIN (-7625 4800) $PN 2
J 0
(-7615 4780);
DISPLAY 0.489362 (-7615 4780);
FORCEPROP 1 LAST MATERIAL X6S
J 0
(-7575 4800);
DISPLAY 0.489362 (-7575 4800);
PAINT SKYBLUE (-7575 4800);
FORCEPROP 1 LAST TOLERANCE 20%
J 0
(-7575 4850);
DISPLAY 0.489362 (-7575 4850);
PAINT SKYBLUE (-7575 4850);
FORCEPROP 1 LAST VALUE 22UF
J 0
(-7575 4950);
DISPLAY 0.489362 (-7575 4950);
PAINT SKYBLUE (-7575 4950);
FORCEPROP 1 LAST PART_NUMBER CH622KMEB02
J 0
(-7575 4750);
DISPLAY 0.489362 (-7575 4750);
PAINT SKYBLUE (-7575 4750);
FORCEPROP 1 LAST VOLTAGE 4V
J 0
(-7575 4900);
DISPLAY 0.489362 (-7575 4900);
PAINT SKYBLUE (-7575 4900);
FORCEPROP 1 LAST PACK_TYPE C0402
J 0
(-7575 4700);
DISPLAY 0.489362 (-7575 4700);
PAINT SKYBLUE (-7575 4700);
FORCEPROP 2 LAST CDS_LIB pure_quanta
J 0
(-7625 4900);
PAINT MONO (-7625 4900);
DISPLAY INVISIBLE (-7625 4900);
FORCEPROP 1 LAST PATH I33
J 0
(-7575 5050);
DISPLAY 0.978723 (-7575 5050);
PAINT WHITE (-7575 5050);
DISPLAY INVISIBLE (-7575 5050);
FORCEADD Q_CAP..1
(-7175 4900);
FORCEPROP 1 LAST LOCATION C2272
J 0
(-7125 5000);
DISPLAY 0.489362 (-7125 5000);
PAINT SKYBLUE (-7125 5000);
FORCEPROP 2 LAST $SEC 1
J 0
(-7125 5100);
DISPLAY 0.680851 (-7125 5100);
PAINT MONO (-7125 5100);
DISPLAY INVISIBLE (-7125 5100);
FORCEPROP 2 LAST CDS_SEC 1
J 0
(-7125 5100);
DISPLAY 1.021277 (-7125 5100);
DISPLAY INVISIBLE (-7125 5100);
FORCEPROP 1 LASTPIN (-7175 5000) $PN 1
J 0
(-7165 4980);
DISPLAY 0.489362 (-7165 4980);
FORCEPROP 1 LASTPIN (-7175 4800) $PN 2
J 0
(-7165 4780);
DISPLAY 0.489362 (-7165 4780);
FORCEPROP 1 LAST MATERIAL X6S
J 0
(-7125 4800);
DISPLAY 0.489362 (-7125 4800);
PAINT SKYBLUE (-7125 4800);
FORCEPROP 1 LAST TOLERANCE 20%
J 0
(-7125 4850);
DISPLAY 0.489362 (-7125 4850);
PAINT SKYBLUE (-7125 4850);
FORCEPROP 1 LAST VALUE 22UF
J 0
(-7125 4950);
DISPLAY 0.489362 (-7125 4950);
PAINT SKYBLUE (-7125 4950);
FORCEPROP 1 LAST PART_NUMBER CH622KMEB02
J 0
(-7125 4750);
DISPLAY 0.489362 (-7125 4750);
PAINT SKYBLUE (-7125 4750);
FORCEPROP 1 LAST VOLTAGE 4V
J 0
(-7125 4900);
DISPLAY 0.489362 (-7125 4900);
PAINT SKYBLUE (-7125 4900);
FORCEPROP 1 LAST PACK_TYPE C0402
J 0
(-7125 4700);
DISPLAY 0.489362 (-7125 4700);
PAINT SKYBLUE (-7125 4700);
FORCEPROP 2 LAST CDS_LIB pure_quanta
J 0
(-7175 4900);
PAINT MONO (-7175 4900);
DISPLAY INVISIBLE (-7175 4900);
FORCEPROP 1 LAST PATH I34
J 0
(-7125 5050);
DISPLAY 0.978723 (-7125 5050);
PAINT WHITE (-7125 5050);
DISPLAY INVISIBLE (-7125 5050);
FORCEADD Q_CAP..1
(-7175 4100);
FORCEPROP 1 LAST LOCATION C2273
J 0
(-7125 4200);
DISPLAY 0.489362 (-7125 4200);
PAINT SKYBLUE (-7125 4200);
FORCEPROP 2 LAST $SEC 1
J 0
(-7125 4300);
DISPLAY 0.680851 (-7125 4300);
PAINT MONO (-7125 4300);
DISPLAY INVISIBLE (-7125 4300);
FORCEPROP 2 LAST CDS_SEC 1
J 0
(-7125 4300);
DISPLAY 1.021277 (-7125 4300);
DISPLAY INVISIBLE (-7125 4300);
FORCEPROP 1 LASTPIN (-7175 4200) $PN 1
J 0
(-7165 4180);
DISPLAY 0.489362 (-7165 4180);
FORCEPROP 1 LASTPIN (-7175 4000) $PN 2
J 0
(-7165 3980);
DISPLAY 0.489362 (-7165 3980);
FORCEPROP 1 LAST MATERIAL X6S
J 0
(-7125 4000);
DISPLAY 0.489362 (-7125 4000);
PAINT SKYBLUE (-7125 4000);
FORCEPROP 1 LAST TOLERANCE 20%
J 0
(-7125 4050);
DISPLAY 0.489362 (-7125 4050);
PAINT SKYBLUE (-7125 4050);
FORCEPROP 1 LAST VALUE 22UF
J 0
(-7125 4150);
DISPLAY 0.489362 (-7125 4150);
PAINT SKYBLUE (-7125 4150);
FORCEPROP 1 LAST PART_NUMBER CH622KMEB02
J 0
(-7125 3950);
DISPLAY 0.489362 (-7125 3950);
PAINT SKYBLUE (-7125 3950);
FORCEPROP 1 LAST VOLTAGE 4V
J 0
(-7125 4100);
DISPLAY 0.489362 (-7125 4100);
PAINT SKYBLUE (-7125 4100);
FORCEPROP 1 LAST PACK_TYPE C0402
J 0
(-7125 3900);
DISPLAY 0.489362 (-7125 3900);
PAINT SKYBLUE (-7125 3900);
FORCEPROP 2 LAST CDS_LIB pure_quanta
J 0
(-7175 4100);
PAINT MONO (-7175 4100);
DISPLAY INVISIBLE (-7175 4100);
FORCEPROP 1 LAST PATH I35
J 0
(-7125 4250);
DISPLAY 0.978723 (-7125 4250);
PAINT WHITE (-7125 4250);
DISPLAY INVISIBLE (-7125 4250);
FORCEADD Q_CAP..1
(-6725 4100);
FORCEPROP 1 LAST LOCATION C2277
J 0
(-6675 4200);
DISPLAY 0.489362 (-6675 4200);
PAINT SKYBLUE (-6675 4200);
FORCEPROP 2 LAST $SEC 1
J 0
(-6675 4300);
DISPLAY 0.680851 (-6675 4300);
PAINT MONO (-6675 4300);
DISPLAY INVISIBLE (-6675 4300);
FORCEPROP 2 LAST CDS_SEC 1
J 0
(-6675 4300);
DISPLAY 1.021277 (-6675 4300);
DISPLAY INVISIBLE (-6675 4300);
FORCEPROP 1 LASTPIN (-6725 4200) $PN 1
J 0
(-6715 4180);
DISPLAY 0.489362 (-6715 4180);
FORCEPROP 1 LASTPIN (-6725 4000) $PN 2
J 0
(-6715 3980);
DISPLAY 0.489362 (-6715 3980);
FORCEPROP 1 LAST MATERIAL X6S
J 0
(-6675 4000);
DISPLAY 0.489362 (-6675 4000);
PAINT SKYBLUE (-6675 4000);
FORCEPROP 1 LAST TOLERANCE 20%
J 0
(-6675 4050);
DISPLAY 0.489362 (-6675 4050);
PAINT SKYBLUE (-6675 4050);
FORCEPROP 1 LAST VALUE 22UF
J 0
(-6675 4150);
DISPLAY 0.489362 (-6675 4150);
PAINT SKYBLUE (-6675 4150);
FORCEPROP 1 LAST PART_NUMBER CH622KMEB02
J 0
(-6675 3950);
DISPLAY 0.489362 (-6675 3950);
PAINT SKYBLUE (-6675 3950);
FORCEPROP 1 LAST VOLTAGE 4V
J 0
(-6675 4100);
DISPLAY 0.489362 (-6675 4100);
PAINT SKYBLUE (-6675 4100);
FORCEPROP 1 LAST PACK_TYPE C0402
J 0
(-6675 3900);
DISPLAY 0.489362 (-6675 3900);
PAINT SKYBLUE (-6675 3900);
FORCEPROP 2 LAST CDS_LIB pure_quanta
J 0
(-6725 4100);
PAINT MONO (-6725 4100);
DISPLAY INVISIBLE (-6725 4100);
FORCEPROP 1 LAST PATH I36
J 0
(-6675 4250);
DISPLAY 0.978723 (-6675 4250);
PAINT WHITE (-6675 4250);
DISPLAY INVISIBLE (-6675 4250);
FORCEADD Q_CAP..1
(-6275 4100);
FORCEPROP 1 LAST LOCATION C2281
J 0
(-6225 4200);
DISPLAY 0.489362 (-6225 4200);
PAINT SKYBLUE (-6225 4200);
FORCEPROP 2 LAST $SEC 1
J 0
(-6225 4300);
DISPLAY 0.680851 (-6225 4300);
PAINT MONO (-6225 4300);
DISPLAY INVISIBLE (-6225 4300);
FORCEPROP 2 LAST CDS_SEC 1
J 0
(-6225 4300);
DISPLAY 1.021277 (-6225 4300);
DISPLAY INVISIBLE (-6225 4300);
FORCEPROP 1 LASTPIN (-6275 4200) $PN 1
J 0
(-6265 4180);
DISPLAY 0.489362 (-6265 4180);
FORCEPROP 1 LASTPIN (-6275 4000) $PN 2
J 0
(-6265 3980);
DISPLAY 0.489362 (-6265 3980);
FORCEPROP 1 LAST MATERIAL X6S
J 0
(-6225 4000);
DISPLAY 0.489362 (-6225 4000);
PAINT SKYBLUE (-6225 4000);
FORCEPROP 1 LAST TOLERANCE 20%
J 0
(-6225 4050);
DISPLAY 0.489362 (-6225 4050);
PAINT SKYBLUE (-6225 4050);
FORCEPROP 1 LAST VALUE 22UF
J 0
(-6225 4150);
DISPLAY 0.489362 (-6225 4150);
PAINT SKYBLUE (-6225 4150);
FORCEPROP 1 LAST PART_NUMBER CH622KMEB02
J 0
(-6225 3950);
DISPLAY 0.489362 (-6225 3950);
PAINT SKYBLUE (-6225 3950);
FORCEPROP 1 LAST VOLTAGE 4V
J 0
(-6225 4100);
DISPLAY 0.489362 (-6225 4100);
PAINT SKYBLUE (-6225 4100);
FORCEPROP 1 LAST PACK_TYPE C0402
J 0
(-6225 3900);
DISPLAY 0.489362 (-6225 3900);
PAINT SKYBLUE (-6225 3900);
FORCEPROP 2 LAST CDS_LIB pure_quanta
J 0
(-6275 4100);
PAINT MONO (-6275 4100);
DISPLAY INVISIBLE (-6275 4100);
FORCEPROP 1 LAST PATH I37
J 0
(-6225 4250);
DISPLAY 0.978723 (-6225 4250);
PAINT WHITE (-6225 4250);
DISPLAY INVISIBLE (-6225 4250);
FORCEADD Q_CAP..1
(-6275 4900);
FORCEPROP 1 LAST LOCATION C2280
J 0
(-6225 5000);
DISPLAY 0.489362 (-6225 5000);
PAINT SKYBLUE (-6225 5000);
FORCEPROP 2 LAST $SEC 1
J 0
(-6225 5100);
DISPLAY 0.680851 (-6225 5100);
PAINT MONO (-6225 5100);
DISPLAY INVISIBLE (-6225 5100);
FORCEPROP 2 LAST CDS_SEC 1
J 0
(-6225 5100);
DISPLAY 1.021277 (-6225 5100);
DISPLAY INVISIBLE (-6225 5100);
FORCEPROP 1 LASTPIN (-6275 5000) $PN 1
J 0
(-6265 4980);
DISPLAY 0.489362 (-6265 4980);
FORCEPROP 1 LASTPIN (-6275 4800) $PN 2
J 0
(-6265 4780);
DISPLAY 0.489362 (-6265 4780);
FORCEPROP 1 LAST MATERIAL X6S
J 0
(-6225 4800);
DISPLAY 0.489362 (-6225 4800);
PAINT SKYBLUE (-6225 4800);
FORCEPROP 1 LAST TOLERANCE 20%
J 0
(-6225 4850);
DISPLAY 0.489362 (-6225 4850);
PAINT SKYBLUE (-6225 4850);
FORCEPROP 1 LAST VALUE 22UF
J 0
(-6225 4950);
DISPLAY 0.489362 (-6225 4950);
PAINT SKYBLUE (-6225 4950);
FORCEPROP 1 LAST PART_NUMBER CH622KMEB02
J 0
(-6225 4750);
DISPLAY 0.489362 (-6225 4750);
PAINT SKYBLUE (-6225 4750);
FORCEPROP 1 LAST VOLTAGE 4V
J 0
(-6225 4900);
DISPLAY 0.489362 (-6225 4900);
PAINT SKYBLUE (-6225 4900);
FORCEPROP 1 LAST PACK_TYPE C0402
J 0
(-6225 4700);
DISPLAY 0.489362 (-6225 4700);
PAINT SKYBLUE (-6225 4700);
FORCEPROP 2 LAST CDS_LIB pure_quanta
J 0
(-6275 4900);
PAINT MONO (-6275 4900);
DISPLAY INVISIBLE (-6275 4900);
FORCEPROP 1 LAST PATH I38
J 0
(-6225 5050);
DISPLAY 0.978723 (-6225 5050);
PAINT WHITE (-6225 5050);
DISPLAY INVISIBLE (-6225 5050);
FORCEADD Q_CAP..1
(-5825 4100);
FORCEPROP 1 LAST LOCATION C2284
J 0
(-5775 4200);
DISPLAY 0.489362 (-5775 4200);
PAINT SKYBLUE (-5775 4200);
FORCEPROP 2 LAST $SEC 1
J 0
(-5775 4300);
DISPLAY 0.680851 (-5775 4300);
PAINT MONO (-5775 4300);
DISPLAY INVISIBLE (-5775 4300);
FORCEPROP 2 LAST CDS_SEC 1
J 0
(-5775 4300);
DISPLAY 1.021277 (-5775 4300);
DISPLAY INVISIBLE (-5775 4300);
FORCEPROP 1 LASTPIN (-5825 4200) $PN 1
J 0
(-5815 4180);
DISPLAY 0.489362 (-5815 4180);
FORCEPROP 1 LASTPIN (-5825 4000) $PN 2
J 0
(-5815 3980);
DISPLAY 0.489362 (-5815 3980);
FORCEPROP 1 LAST MATERIAL X6S
J 0
(-5775 4000);
DISPLAY 0.489362 (-5775 4000);
PAINT SKYBLUE (-5775 4000);
FORCEPROP 1 LAST TOLERANCE 20%
J 0
(-5775 4050);
DISPLAY 0.489362 (-5775 4050);
PAINT SKYBLUE (-5775 4050);
FORCEPROP 1 LAST VALUE 22UF
J 0
(-5775 4150);
DISPLAY 0.489362 (-5775 4150);
PAINT SKYBLUE (-5775 4150);
FORCEPROP 1 LAST PART_NUMBER CH622KMEB02
J 0
(-5775 3950);
DISPLAY 0.489362 (-5775 3950);
PAINT SKYBLUE (-5775 3950);
FORCEPROP 1 LAST VOLTAGE 4V
J 0
(-5775 4100);
DISPLAY 0.489362 (-5775 4100);
PAINT SKYBLUE (-5775 4100);
FORCEPROP 1 LAST PACK_TYPE C0402
J 0
(-5775 3900);
DISPLAY 0.489362 (-5775 3900);
PAINT SKYBLUE (-5775 3900);
FORCEPROP 2 LAST CDS_LIB pure_quanta
J 0
(-5825 4100);
PAINT MONO (-5825 4100);
DISPLAY INVISIBLE (-5825 4100);
FORCEPROP 1 LAST PATH I39
J 0
(-5775 4250);
DISPLAY 0.978723 (-5775 4250);
PAINT WHITE (-5775 4250);
DISPLAY INVISIBLE (-5775 4250);
FORCEADD UNIVERSAL_POWER..1
(-8500 1850);
FORCEPROP 3 LASTPIN (-8500 1800) SIG_NAME PVDD11_S3_P1\g
J 0
(-8490 1810);
DISPLAY 0.659574 (-8490 1810);
PAINT MONO (-8490 1810);
DISPLAY INVISIBLE (-8490 1810);
FORCEPROP 1 LAST HDL_POWER PVDD11_S3_P1
J 1
(-8500 1900);
DISPLAY 0.489362 (-8500 1900);
PAINT GREEN (-8500 1900);
FORCEPROP 2 LAST CDS_LIB pure_quanta_power
J 0
(-8500 1850);
DISPLAY INVISIBLE (-8500 1850);
FORCEPROP 1 LAST PATH I4
J 0
(-8450 1875);
DISPLAY 0.872340 (-8450 1875);
PAINT AQUA (-8450 1875);
DISPLAY INVISIBLE (-8450 1875);
FORCEADD Q_CAP..1
(-5825 4900);
FORCEPROP 1 LAST LOCATION C2283
J 0
(-5775 5000);
DISPLAY 0.489362 (-5775 5000);
PAINT SKYBLUE (-5775 5000);
FORCEPROP 2 LAST $SEC 1
J 0
(-5775 5100);
DISPLAY 0.680851 (-5775 5100);
PAINT MONO (-5775 5100);
DISPLAY INVISIBLE (-5775 5100);
FORCEPROP 2 LAST CDS_SEC 1
J 0
(-5775 5100);
DISPLAY 1.021277 (-5775 5100);
DISPLAY INVISIBLE (-5775 5100);
FORCEPROP 1 LASTPIN (-5825 5000) $PN 1
J 0
(-5815 4980);
DISPLAY 0.489362 (-5815 4980);
FORCEPROP 1 LASTPIN (-5825 4800) $PN 2
J 0
(-5815 4780);
DISPLAY 0.489362 (-5815 4780);
FORCEPROP 1 LAST MATERIAL X6S
J 0
(-5775 4800);
DISPLAY 0.489362 (-5775 4800);
PAINT SKYBLUE (-5775 4800);
FORCEPROP 1 LAST TOLERANCE 20%
J 0
(-5775 4850);
DISPLAY 0.489362 (-5775 4850);
PAINT SKYBLUE (-5775 4850);
FORCEPROP 1 LAST VALUE 22UF
J 0
(-5775 4950);
DISPLAY 0.489362 (-5775 4950);
PAINT SKYBLUE (-5775 4950);
FORCEPROP 1 LAST PART_NUMBER CH622KMEB02
J 0
(-5775 4750);
DISPLAY 0.489362 (-5775 4750);
PAINT SKYBLUE (-5775 4750);
FORCEPROP 1 LAST VOLTAGE 4V
J 0
(-5775 4900);
DISPLAY 0.489362 (-5775 4900);
PAINT SKYBLUE (-5775 4900);
FORCEPROP 1 LAST PACK_TYPE C0402
J 0
(-5775 4700);
DISPLAY 0.489362 (-5775 4700);
PAINT SKYBLUE (-5775 4700);
FORCEPROP 2 LAST CDS_LIB pure_quanta
J 0
(-5825 4900);
PAINT MONO (-5825 4900);
DISPLAY INVISIBLE (-5825 4900);
FORCEPROP 1 LAST PATH I40
J 0
(-5775 5050);
DISPLAY 0.978723 (-5775 5050);
PAINT WHITE (-5775 5050);
DISPLAY INVISIBLE (-5775 5050);
FORCEADD Q_CAP..1
(-5375 4100);
FORCEPROP 1 LAST LOCATION C3906
J 0
(-5325 4200);
DISPLAY 0.489362 (-5325 4200);
PAINT SKYBLUE (-5325 4200);
FORCEPROP 2 LAST $SEC 1
J 0
(-5325 4300);
DISPLAY 0.680851 (-5325 4300);
PAINT MONO (-5325 4300);
DISPLAY INVISIBLE (-5325 4300);
FORCEPROP 2 LAST CDS_SEC 1
J 0
(-5325 4300);
DISPLAY 1.021277 (-5325 4300);
DISPLAY INVISIBLE (-5325 4300);
FORCEPROP 1 LASTPIN (-5375 4200) $PN 1
J 0
(-5365 4180);
DISPLAY 0.489362 (-5365 4180);
FORCEPROP 1 LASTPIN (-5375 4000) $PN 2
J 0
(-5365 3980);
DISPLAY 0.489362 (-5365 3980);
FORCEPROP 1 LAST MATERIAL X6S
J 0
(-5325 4000);
DISPLAY 0.489362 (-5325 4000);
PAINT SKYBLUE (-5325 4000);
FORCEPROP 1 LAST TOLERANCE 20%
J 0
(-5325 4050);
DISPLAY 0.489362 (-5325 4050);
PAINT SKYBLUE (-5325 4050);
FORCEPROP 1 LAST VALUE 22UF
J 0
(-5325 4150);
DISPLAY 0.489362 (-5325 4150);
PAINT SKYBLUE (-5325 4150);
FORCEPROP 1 LAST PART_NUMBER CH622KMEB02
J 0
(-5325 3950);
DISPLAY 0.489362 (-5325 3950);
PAINT SKYBLUE (-5325 3950);
FORCEPROP 1 LAST VOLTAGE 4V
J 0
(-5325 4100);
DISPLAY 0.489362 (-5325 4100);
PAINT SKYBLUE (-5325 4100);
FORCEPROP 1 LAST PACK_TYPE C0402
J 0
(-5325 3900);
DISPLAY 0.489362 (-5325 3900);
PAINT SKYBLUE (-5325 3900);
FORCEPROP 2 LAST CDS_LIB pure_quanta
J 0
(-5375 4100);
PAINT MONO (-5375 4100);
DISPLAY INVISIBLE (-5375 4100);
FORCEPROP 1 LAST PATH I41
J 0
(-5325 4250);
DISPLAY 0.978723 (-5325 4250);
PAINT WHITE (-5325 4250);
DISPLAY INVISIBLE (-5325 4250);
FORCEADD Q_CAP..1
(-5375 4900);
FORCEPROP 1 LAST LOCATION C2286
J 0
(-5325 5000);
DISPLAY 0.489362 (-5325 5000);
PAINT SKYBLUE (-5325 5000);
FORCEPROP 2 LAST $SEC 1
J 0
(-5325 5100);
DISPLAY 0.680851 (-5325 5100);
PAINT MONO (-5325 5100);
DISPLAY INVISIBLE (-5325 5100);
FORCEPROP 2 LAST CDS_SEC 1
J 0
(-5325 5100);
DISPLAY 1.021277 (-5325 5100);
DISPLAY INVISIBLE (-5325 5100);
FORCEPROP 1 LASTPIN (-5375 5000) $PN 1
J 0
(-5365 4980);
DISPLAY 0.489362 (-5365 4980);
FORCEPROP 1 LASTPIN (-5375 4800) $PN 2
J 0
(-5365 4780);
DISPLAY 0.489362 (-5365 4780);
FORCEPROP 1 LAST MATERIAL X6S
J 0
(-5325 4800);
DISPLAY 0.489362 (-5325 4800);
PAINT SKYBLUE (-5325 4800);
FORCEPROP 1 LAST TOLERANCE 20%
J 0
(-5325 4850);
DISPLAY 0.489362 (-5325 4850);
PAINT SKYBLUE (-5325 4850);
FORCEPROP 1 LAST VALUE 22UF
J 0
(-5325 4950);
DISPLAY 0.489362 (-5325 4950);
PAINT SKYBLUE (-5325 4950);
FORCEPROP 1 LAST PART_NUMBER CH622KMEB02
J 0
(-5325 4750);
DISPLAY 0.489362 (-5325 4750);
PAINT SKYBLUE (-5325 4750);
FORCEPROP 1 LAST VOLTAGE 4V
J 0
(-5325 4900);
DISPLAY 0.489362 (-5325 4900);
PAINT SKYBLUE (-5325 4900);
FORCEPROP 1 LAST PACK_TYPE C0402
J 0
(-5325 4700);
DISPLAY 0.489362 (-5325 4700);
PAINT SKYBLUE (-5325 4700);
FORCEPROP 2 LAST CDS_LIB pure_quanta
J 0
(-5375 4900);
PAINT MONO (-5375 4900);
DISPLAY INVISIBLE (-5375 4900);
FORCEPROP 1 LAST PATH I42
J 0
(-5325 5050);
DISPLAY 0.978723 (-5325 5050);
PAINT WHITE (-5325 5050);
DISPLAY INVISIBLE (-5325 5050);
FORCEADD Q_CAP..1
(-4925 4100);
FORCEPROP 1 LAST LOCATION C3907
J 0
(-4875 4200);
DISPLAY 0.489362 (-4875 4200);
PAINT SKYBLUE (-4875 4200);
FORCEPROP 2 LAST $SEC 1
J 0
(-4875 4300);
DISPLAY 0.680851 (-4875 4300);
PAINT MONO (-4875 4300);
DISPLAY INVISIBLE (-4875 4300);
FORCEPROP 2 LAST CDS_SEC 1
J 0
(-4875 4300);
DISPLAY 1.021277 (-4875 4300);
DISPLAY INVISIBLE (-4875 4300);
FORCEPROP 1 LASTPIN (-4925 4200) $PN 1
J 0
(-4915 4180);
DISPLAY 0.489362 (-4915 4180);
FORCEPROP 1 LASTPIN (-4925 4000) $PN 2
J 0
(-4915 3980);
DISPLAY 0.489362 (-4915 3980);
FORCEPROP 1 LAST MATERIAL X6S
J 0
(-4875 4000);
DISPLAY 0.489362 (-4875 4000);
PAINT SKYBLUE (-4875 4000);
FORCEPROP 1 LAST TOLERANCE 20%
J 0
(-4875 4050);
DISPLAY 0.489362 (-4875 4050);
PAINT SKYBLUE (-4875 4050);
FORCEPROP 1 LAST VALUE 22UF
J 0
(-4875 4150);
DISPLAY 0.489362 (-4875 4150);
PAINT SKYBLUE (-4875 4150);
FORCEPROP 1 LAST PART_NUMBER CH622KMEB02
J 0
(-4875 3950);
DISPLAY 0.489362 (-4875 3950);
PAINT SKYBLUE (-4875 3950);
FORCEPROP 1 LAST VOLTAGE 4V
J 0
(-4875 4100);
DISPLAY 0.489362 (-4875 4100);
PAINT SKYBLUE (-4875 4100);
FORCEPROP 1 LAST PACK_TYPE C0402
J 0
(-4875 3900);
DISPLAY 0.489362 (-4875 3900);
PAINT SKYBLUE (-4875 3900);
FORCEPROP 2 LAST CDS_LIB pure_quanta
J 0
(-4925 4100);
PAINT MONO (-4925 4100);
DISPLAY INVISIBLE (-4925 4100);
FORCEPROP 1 LAST PATH I43
J 0
(-4875 4250);
DISPLAY 0.978723 (-4875 4250);
PAINT WHITE (-4875 4250);
DISPLAY INVISIBLE (-4875 4250);
FORCEADD Q_CAP..1
(-4925 4900);
FORCEPROP 1 LAST LOCATION C2288
J 0
(-4875 5000);
DISPLAY 0.489362 (-4875 5000);
PAINT SKYBLUE (-4875 5000);
FORCEPROP 2 LAST $SEC 1
J 0
(-4875 5100);
DISPLAY 0.680851 (-4875 5100);
PAINT MONO (-4875 5100);
DISPLAY INVISIBLE (-4875 5100);
FORCEPROP 2 LAST CDS_SEC 1
J 0
(-4875 5100);
DISPLAY 1.021277 (-4875 5100);
DISPLAY INVISIBLE (-4875 5100);
FORCEPROP 1 LASTPIN (-4925 5000) $PN 1
J 0
(-4915 4980);
DISPLAY 0.489362 (-4915 4980);
FORCEPROP 1 LASTPIN (-4925 4800) $PN 2
J 0
(-4915 4780);
DISPLAY 0.489362 (-4915 4780);
FORCEPROP 1 LAST MATERIAL X6S
J 0
(-4875 4800);
DISPLAY 0.489362 (-4875 4800);
PAINT SKYBLUE (-4875 4800);
FORCEPROP 1 LAST TOLERANCE 20%
J 0
(-4875 4850);
DISPLAY 0.489362 (-4875 4850);
PAINT SKYBLUE (-4875 4850);
FORCEPROP 1 LAST VALUE 22UF
J 0
(-4875 4950);
DISPLAY 0.489362 (-4875 4950);
PAINT SKYBLUE (-4875 4950);
FORCEPROP 1 LAST PART_NUMBER CH622KMEB02
J 0
(-4875 4750);
DISPLAY 0.489362 (-4875 4750);
PAINT SKYBLUE (-4875 4750);
FORCEPROP 1 LAST VOLTAGE 4V
J 0
(-4875 4900);
DISPLAY 0.489362 (-4875 4900);
PAINT SKYBLUE (-4875 4900);
FORCEPROP 1 LAST PACK_TYPE C0402
J 0
(-4875 4700);
DISPLAY 0.489362 (-4875 4700);
PAINT SKYBLUE (-4875 4700);
FORCEPROP 2 LAST CDS_LIB pure_quanta
J 0
(-4925 4900);
PAINT MONO (-4925 4900);
DISPLAY INVISIBLE (-4925 4900);
FORCEPROP 1 LAST PATH I44
J 0
(-4875 5050);
DISPLAY 0.978723 (-4875 5050);
PAINT WHITE (-4875 5050);
DISPLAY INVISIBLE (-4875 5050);
FORCEADD Q_CAP..1
(-4525 4100);
FORCEPROP 1 LAST LOCATION C3908
J 0
(-4475 4200);
DISPLAY 0.489362 (-4475 4200);
PAINT SKYBLUE (-4475 4200);
FORCEPROP 2 LAST $SEC 1
J 0
(-4475 4300);
DISPLAY 0.680851 (-4475 4300);
PAINT MONO (-4475 4300);
DISPLAY INVISIBLE (-4475 4300);
FORCEPROP 2 LAST CDS_SEC 1
J 0
(-4475 4300);
DISPLAY 1.021277 (-4475 4300);
DISPLAY INVISIBLE (-4475 4300);
FORCEPROP 1 LASTPIN (-4525 4200) $PN 1
J 0
(-4515 4180);
DISPLAY 0.489362 (-4515 4180);
FORCEPROP 1 LASTPIN (-4525 4000) $PN 2
J 0
(-4515 3980);
DISPLAY 0.489362 (-4515 3980);
FORCEPROP 1 LAST MATERIAL X6S
J 0
(-4475 4000);
DISPLAY 0.489362 (-4475 4000);
PAINT SKYBLUE (-4475 4000);
FORCEPROP 1 LAST TOLERANCE 20%
J 0
(-4475 4050);
DISPLAY 0.489362 (-4475 4050);
PAINT SKYBLUE (-4475 4050);
FORCEPROP 1 LAST VALUE 22UF
J 0
(-4475 4150);
DISPLAY 0.489362 (-4475 4150);
PAINT SKYBLUE (-4475 4150);
FORCEPROP 1 LAST PART_NUMBER CH622KMEB02
J 0
(-4475 3950);
DISPLAY 0.489362 (-4475 3950);
PAINT SKYBLUE (-4475 3950);
FORCEPROP 1 LAST VOLTAGE 4V
J 0
(-4475 4100);
DISPLAY 0.489362 (-4475 4100);
PAINT SKYBLUE (-4475 4100);
FORCEPROP 1 LAST PACK_TYPE C0402
J 0
(-4475 3900);
DISPLAY 0.489362 (-4475 3900);
PAINT SKYBLUE (-4475 3900);
FORCEPROP 2 LAST CDS_LIB pure_quanta
J 0
(-4525 4100);
PAINT MONO (-4525 4100);
DISPLAY INVISIBLE (-4525 4100);
FORCEPROP 1 LAST PATH I45
J 0
(-4475 4250);
DISPLAY 0.978723 (-4475 4250);
PAINT WHITE (-4475 4250);
DISPLAY INVISIBLE (-4475 4250);
FORCEADD UNIVERSAL_GND..1
(-4525 4525);
FORCEPROP 3 LASTPIN (-4525 4575) SIG_NAME GND\g
J 0
(-4515 4585);
DISPLAY 0.659574 (-4515 4585);
PAINT MONO (-4515 4585);
DISPLAY INVISIBLE (-4515 4585);
FORCEPROP 2 LAST CDS_LIB pure_quanta_power
J 0
(-4525 4525);
PAINT MONO (-4525 4525);
DISPLAY INVISIBLE (-4525 4525);
FORCEPROP 1 LAST PATH I46
J 0
(-4450 4525);
DISPLAY 0.872340 (-4450 4525);
PAINT AQUA (-4450 4525);
DISPLAY INVISIBLE (-4450 4525);
FORCEPROP 1 LAST HDL_POWER GND
J 1
(-4500 4450);
DISPLAY 0.872340 (-4500 4450);
PAINT GREEN (-4500 4450);
DISPLAY INVISIBLE (-4500 4450);
FORCEADD Q_CAP..1
(-4525 4900);
FORCEPROP 1 LAST LOCATION C2290
J 0
(-4475 5000);
DISPLAY 0.489362 (-4475 5000);
PAINT SKYBLUE (-4475 5000);
FORCEPROP 2 LAST $SEC 1
J 0
(-4475 5100);
DISPLAY 0.680851 (-4475 5100);
PAINT MONO (-4475 5100);
DISPLAY INVISIBLE (-4475 5100);
FORCEPROP 2 LAST CDS_SEC 1
J 0
(-4475 5100);
DISPLAY 1.021277 (-4475 5100);
DISPLAY INVISIBLE (-4475 5100);
FORCEPROP 1 LASTPIN (-4525 5000) $PN 1
J 0
(-4515 4980);
DISPLAY 0.489362 (-4515 4980);
FORCEPROP 1 LASTPIN (-4525 4800) $PN 2
J 0
(-4515 4780);
DISPLAY 0.489362 (-4515 4780);
FORCEPROP 1 LAST MATERIAL X6S
J 0
(-4475 4800);
DISPLAY 0.489362 (-4475 4800);
PAINT SKYBLUE (-4475 4800);
FORCEPROP 1 LAST TOLERANCE 20%
J 0
(-4475 4850);
DISPLAY 0.489362 (-4475 4850);
PAINT SKYBLUE (-4475 4850);
FORCEPROP 1 LAST VALUE 22UF
J 0
(-4475 4950);
DISPLAY 0.489362 (-4475 4950);
PAINT SKYBLUE (-4475 4950);
FORCEPROP 1 LAST PART_NUMBER CH622KMEB02
J 0
(-4475 4750);
DISPLAY 0.489362 (-4475 4750);
PAINT SKYBLUE (-4475 4750);
FORCEPROP 1 LAST VOLTAGE 4V
J 0
(-4475 4900);
DISPLAY 0.489362 (-4475 4900);
PAINT SKYBLUE (-4475 4900);
FORCEPROP 1 LAST PACK_TYPE C0402
J 0
(-4475 4700);
DISPLAY 0.489362 (-4475 4700);
PAINT SKYBLUE (-4475 4700);
FORCEPROP 2 LAST CDS_LIB pure_quanta
J 0
(-4525 4900);
PAINT MONO (-4525 4900);
DISPLAY INVISIBLE (-4525 4900);
FORCEPROP 1 LAST PATH I47
J 0
(-4475 5050);
DISPLAY 0.978723 (-4475 5050);
PAINT WHITE (-4475 5050);
DISPLAY INVISIBLE (-4475 5050);
FORCEADD UNIVERSAL_POWER..1
(-3600 3650);
FORCEPROP 3 LASTPIN (-3600 3600) SIG_NAME PVDD18_S5_P1\g
J 0
(-3590 3610);
DISPLAY 0.659574 (-3590 3610);
PAINT MONO (-3590 3610);
DISPLAY INVISIBLE (-3590 3610);
FORCEPROP 1 LAST HDL_POWER PVDD18_S5_P1
J 1
(-3600 3700);
DISPLAY 0.489362 (-3600 3700);
PAINT GREEN (-3600 3700);
FORCEPROP 2 LAST CDS_LIB pure_quanta_power
J 0
(-3600 3650);
DISPLAY INVISIBLE (-3600 3650);
FORCEPROP 1 LAST PATH I48
J 0
(-3550 3675);
DISPLAY 0.872340 (-3550 3675);
PAINT AQUA (-3550 3675);
DISPLAY INVISIBLE (-3550 3675);
FORCEADD Q_CAP..1
(-3600 3375);
FORCEPROP 1 LAST LOCATION C2292
J 0
(-3550 3475);
DISPLAY 0.489362 (-3550 3475);
PAINT SKYBLUE (-3550 3475);
FORCEPROP 2 LAST $SEC 1
J 0
(-3550 3575);
DISPLAY 0.680851 (-3550 3575);
PAINT MONO (-3550 3575);
DISPLAY INVISIBLE (-3550 3575);
FORCEPROP 2 LAST CDS_SEC 1
J 0
(-3550 3575);
DISPLAY 1.021277 (-3550 3575);
DISPLAY INVISIBLE (-3550 3575);
FORCEPROP 1 LASTPIN (-3600 3475) $PN 1
J 0
(-3590 3455);
DISPLAY 0.489362 (-3590 3455);
FORCEPROP 1 LASTPIN (-3600 3275) $PN 2
J 0
(-3590 3255);
DISPLAY 0.489362 (-3590 3255);
FORCEPROP 1 LAST MATERIAL X6S
J 0
(-3550 3275);
DISPLAY 0.489362 (-3550 3275);
PAINT SKYBLUE (-3550 3275);
FORCEPROP 1 LAST TOLERANCE 20%
J 0
(-3550 3325);
DISPLAY 0.489362 (-3550 3325);
PAINT SKYBLUE (-3550 3325);
FORCEPROP 1 LAST VALUE 22UF
J 0
(-3550 3425);
DISPLAY 0.489362 (-3550 3425);
PAINT SKYBLUE (-3550 3425);
FORCEPROP 1 LAST PART_NUMBER CH622KMEB02
J 0
(-3550 3225);
DISPLAY 0.489362 (-3550 3225);
PAINT SKYBLUE (-3550 3225);
FORCEPROP 1 LAST VOLTAGE 4V
J 0
(-3550 3375);
DISPLAY 0.489362 (-3550 3375);
PAINT SKYBLUE (-3550 3375);
FORCEPROP 1 LAST PACK_TYPE C0402
J 0
(-3550 3175);
DISPLAY 0.489362 (-3550 3175);
PAINT SKYBLUE (-3550 3175);
FORCEPROP 2 LAST CDS_LIB pure_quanta
J 0
(-3600 3375);
PAINT MONO (-3600 3375);
DISPLAY INVISIBLE (-3600 3375);
FORCEPROP 1 LAST PATH I49
J 0
(-3550 3525);
DISPLAY 0.978723 (-3550 3525);
PAINT WHITE (-3550 3525);
DISPLAY INVISIBLE (-3550 3525);
FORCEADD Q_CAP..1
(-8525 3375);
FORCEPROP 1 LAST LOCATION C3900
J 0
(-8475 3475);
DISPLAY 0.489362 (-8475 3475);
PAINT SKYBLUE (-8475 3475);
FORCEPROP 2 LAST $SEC 1
J 0
(-8475 3575);
DISPLAY 0.680851 (-8475 3575);
PAINT MONO (-8475 3575);
DISPLAY INVISIBLE (-8475 3575);
FORCEPROP 2 LAST CDS_SEC 1
J 0
(-8475 3575);
DISPLAY 1.021277 (-8475 3575);
DISPLAY INVISIBLE (-8475 3575);
FORCEPROP 1 LASTPIN (-8525 3475) $PN 1
J 0
(-8515 3455);
DISPLAY 0.489362 (-8515 3455);
FORCEPROP 1 LASTPIN (-8525 3275) $PN 2
J 0
(-8515 3255);
DISPLAY 0.489362 (-8515 3255);
FORCEPROP 1 LAST MATERIAL X6S
J 0
(-8475 3275);
DISPLAY 0.489362 (-8475 3275);
PAINT SKYBLUE (-8475 3275);
FORCEPROP 1 LAST TOLERANCE 20%
J 0
(-8475 3325);
DISPLAY 0.489362 (-8475 3325);
PAINT SKYBLUE (-8475 3325);
FORCEPROP 1 LAST VALUE 22UF
J 0
(-8475 3425);
DISPLAY 0.489362 (-8475 3425);
PAINT SKYBLUE (-8475 3425);
FORCEPROP 1 LAST PART_NUMBER CH622KMEB02
J 0
(-8475 3225);
DISPLAY 0.489362 (-8475 3225);
PAINT SKYBLUE (-8475 3225);
FORCEPROP 1 LAST VOLTAGE 4V
J 0
(-8475 3375);
DISPLAY 0.489362 (-8475 3375);
PAINT SKYBLUE (-8475 3375);
FORCEPROP 1 LAST PACK_TYPE C0402
J 0
(-8475 3175);
DISPLAY 0.489362 (-8475 3175);
PAINT SKYBLUE (-8475 3175);
FORCEPROP 2 LAST CDS_LIB pure_quanta
J 0
(-8525 3375);
PAINT MONO (-8525 3375);
DISPLAY INVISIBLE (-8525 3375);
FORCEPROP 1 LAST PATH I5
J 0
(-8475 3525);
DISPLAY 0.978723 (-8475 3525);
PAINT WHITE (-8475 3525);
DISPLAY INVISIBLE (-8475 3525);
FORCEADD Q_CAP..1
(-3150 3375);
FORCEPROP 1 LAST LOCATION C2293
J 0
(-3100 3475);
DISPLAY 0.489362 (-3100 3475);
PAINT SKYBLUE (-3100 3475);
FORCEPROP 2 LAST $SEC 1
J 0
(-3100 3575);
DISPLAY 0.680851 (-3100 3575);
PAINT MONO (-3100 3575);
DISPLAY INVISIBLE (-3100 3575);
FORCEPROP 2 LAST CDS_SEC 1
J 0
(-3100 3575);
DISPLAY 1.021277 (-3100 3575);
DISPLAY INVISIBLE (-3100 3575);
FORCEPROP 1 LASTPIN (-3150 3475) $PN 1
J 0
(-3140 3455);
DISPLAY 0.489362 (-3140 3455);
FORCEPROP 1 LASTPIN (-3150 3275) $PN 2
J 0
(-3140 3255);
DISPLAY 0.489362 (-3140 3255);
FORCEPROP 1 LAST MATERIAL X6S
J 0
(-3100 3275);
DISPLAY 0.489362 (-3100 3275);
PAINT SKYBLUE (-3100 3275);
FORCEPROP 1 LAST TOLERANCE 20%
J 0
(-3100 3325);
DISPLAY 0.489362 (-3100 3325);
PAINT SKYBLUE (-3100 3325);
FORCEPROP 1 LAST VALUE 22UF
J 0
(-3100 3425);
DISPLAY 0.489362 (-3100 3425);
PAINT SKYBLUE (-3100 3425);
FORCEPROP 1 LAST PART_NUMBER CH622KMEB02
J 0
(-3100 3225);
DISPLAY 0.489362 (-3100 3225);
PAINT SKYBLUE (-3100 3225);
FORCEPROP 1 LAST VOLTAGE 4V
J 0
(-3100 3375);
DISPLAY 0.489362 (-3100 3375);
PAINT SKYBLUE (-3100 3375);
FORCEPROP 1 LAST PACK_TYPE C0402
J 0
(-3100 3175);
DISPLAY 0.489362 (-3100 3175);
PAINT SKYBLUE (-3100 3175);
FORCEPROP 2 LAST CDS_LIB pure_quanta
J 0
(-3150 3375);
PAINT MONO (-3150 3375);
DISPLAY INVISIBLE (-3150 3375);
FORCEPROP 1 LAST PATH I50
J 0
(-3100 3525);
DISPLAY 0.978723 (-3100 3525);
PAINT WHITE (-3100 3525);
DISPLAY INVISIBLE (-3100 3525);
FORCEADD UNIVERSAL_GND..1
(-2700 3025);
FORCEPROP 3 LASTPIN (-2700 3075) SIG_NAME GND\g
J 0
(-2690 3085);
DISPLAY 0.659574 (-2690 3085);
PAINT MONO (-2690 3085);
DISPLAY INVISIBLE (-2690 3085);
FORCEPROP 2 LAST CDS_LIB pure_quanta_power
J 0
(-2700 3025);
DISPLAY INVISIBLE (-2700 3025);
FORCEPROP 1 LAST PATH I51
J 0
(-2625 3025);
DISPLAY 0.872340 (-2625 3025);
PAINT AQUA (-2625 3025);
DISPLAY INVISIBLE (-2625 3025);
FORCEPROP 1 LAST HDL_POWER GND
J 1
(-2675 2950);
DISPLAY 0.872340 (-2675 2950);
PAINT GREEN (-2675 2950);
DISPLAY INVISIBLE (-2675 2950);
FORCEADD Q_CAP..1
(-2700 3375);
FORCEPROP 1 LAST LOCATION C3909
J 0
(-2650 3475);
DISPLAY 0.489362 (-2650 3475);
PAINT SKYBLUE (-2650 3475);
FORCEPROP 2 LAST $SEC 1
J 0
(-2650 3575);
DISPLAY 0.680851 (-2650 3575);
PAINT MONO (-2650 3575);
DISPLAY INVISIBLE (-2650 3575);
FORCEPROP 2 LAST CDS_SEC 1
J 0
(-2650 3575);
DISPLAY 1.021277 (-2650 3575);
DISPLAY INVISIBLE (-2650 3575);
FORCEPROP 1 LASTPIN (-2700 3475) $PN 1
J 0
(-2690 3455);
DISPLAY 0.489362 (-2690 3455);
FORCEPROP 1 LASTPIN (-2700 3275) $PN 2
J 0
(-2690 3255);
DISPLAY 0.489362 (-2690 3255);
FORCEPROP 1 LAST MATERIAL X6S
J 0
(-2650 3275);
DISPLAY 0.489362 (-2650 3275);
PAINT SKYBLUE (-2650 3275);
FORCEPROP 1 LAST TOLERANCE 20%
J 0
(-2650 3325);
DISPLAY 0.489362 (-2650 3325);
PAINT SKYBLUE (-2650 3325);
FORCEPROP 1 LAST VALUE 22UF
J 0
(-2650 3425);
DISPLAY 0.489362 (-2650 3425);
PAINT SKYBLUE (-2650 3425);
FORCEPROP 1 LAST PART_NUMBER CH622KMEB02
J 0
(-2650 3225);
DISPLAY 0.489362 (-2650 3225);
PAINT SKYBLUE (-2650 3225);
FORCEPROP 1 LAST VOLTAGE 4V
J 0
(-2650 3375);
DISPLAY 0.489362 (-2650 3375);
PAINT SKYBLUE (-2650 3375);
FORCEPROP 1 LAST PACK_TYPE C0402
J 0
(-2650 3175);
DISPLAY 0.489362 (-2650 3175);
PAINT SKYBLUE (-2650 3175);
FORCEPROP 2 LAST CDS_LIB pure_quanta
J 0
(-2700 3375);
PAINT MONO (-2700 3375);
DISPLAY INVISIBLE (-2700 3375);
FORCEPROP 1 LAST PATH I52
J 0
(-2650 3525);
DISPLAY 0.978723 (-2650 3525);
PAINT WHITE (-2650 3525);
DISPLAY INVISIBLE (-2650 3525);
FORCEADD Q_CAP..1
(-3600 4975);
FORCEPROP 1 LAST LOCATION C2260
J 0
(-3550 5075);
DISPLAY 0.489362 (-3550 5075);
PAINT SKYBLUE (-3550 5075);
FORCEPROP 2 LAST $SEC 1
J 0
(-3550 5175);
DISPLAY 0.680851 (-3550 5175);
PAINT MONO (-3550 5175);
DISPLAY INVISIBLE (-3550 5175);
FORCEPROP 2 LAST CDS_SEC 1
J 0
(-3550 5175);
DISPLAY 1.021277 (-3550 5175);
DISPLAY INVISIBLE (-3550 5175);
FORCEPROP 1 LASTPIN (-3600 5075) $PN 1
J 0
(-3590 5055);
DISPLAY 0.489362 (-3590 5055);
FORCEPROP 1 LASTPIN (-3600 4875) $PN 2
J 0
(-3590 4855);
DISPLAY 0.489362 (-3590 4855);
FORCEPROP 1 LAST MATERIAL X6S
J 0
(-3550 4875);
DISPLAY 0.489362 (-3550 4875);
PAINT SKYBLUE (-3550 4875);
FORCEPROP 1 LAST TOLERANCE 20%
J 0
(-3550 4925);
DISPLAY 0.489362 (-3550 4925);
PAINT SKYBLUE (-3550 4925);
FORCEPROP 1 LAST VALUE 22UF
J 0
(-3550 5025);
DISPLAY 0.489362 (-3550 5025);
PAINT SKYBLUE (-3550 5025);
FORCEPROP 1 LAST PART_NUMBER CH622KMEB02
J 0
(-3550 4825);
DISPLAY 0.489362 (-3550 4825);
PAINT SKYBLUE (-3550 4825);
FORCEPROP 1 LAST VOLTAGE 4V
J 0
(-3550 4975);
DISPLAY 0.489362 (-3550 4975);
PAINT SKYBLUE (-3550 4975);
FORCEPROP 1 LAST PACK_TYPE C0402
J 0
(-3550 4775);
DISPLAY 0.489362 (-3550 4775);
PAINT SKYBLUE (-3550 4775);
FORCEPROP 2 LAST CDS_LIB pure_quanta
J 0
(-3600 4975);
PAINT MONO (-3600 4975);
DISPLAY INVISIBLE (-3600 4975);
FORCEPROP 1 LAST PATH I53
J 0
(-3550 5125);
DISPLAY 0.978723 (-3550 5125);
PAINT WHITE (-3550 5125);
DISPLAY INVISIBLE (-3550 5125);
FORCEADD Q_CAP..1
(-3150 4975);
FORCEPROP 1 LAST LOCATION C2265
J 0
(-3100 5075);
DISPLAY 0.489362 (-3100 5075);
PAINT SKYBLUE (-3100 5075);
FORCEPROP 2 LAST $SEC 1
J 0
(-3100 5175);
DISPLAY 0.680851 (-3100 5175);
PAINT MONO (-3100 5175);
DISPLAY INVISIBLE (-3100 5175);
FORCEPROP 2 LAST CDS_SEC 1
J 0
(-3100 5175);
DISPLAY 1.021277 (-3100 5175);
DISPLAY INVISIBLE (-3100 5175);
FORCEPROP 1 LASTPIN (-3150 5075) $PN 1
J 0
(-3140 5055);
DISPLAY 0.489362 (-3140 5055);
FORCEPROP 1 LASTPIN (-3150 4875) $PN 2
J 0
(-3140 4855);
DISPLAY 0.489362 (-3140 4855);
FORCEPROP 1 LAST MATERIAL X6S
J 0
(-3100 4875);
DISPLAY 0.489362 (-3100 4875);
PAINT SKYBLUE (-3100 4875);
FORCEPROP 1 LAST TOLERANCE 20%
J 0
(-3100 4925);
DISPLAY 0.489362 (-3100 4925);
PAINT SKYBLUE (-3100 4925);
FORCEPROP 1 LAST VALUE 22UF
J 0
(-3100 5025);
DISPLAY 0.489362 (-3100 5025);
PAINT SKYBLUE (-3100 5025);
FORCEPROP 1 LAST PART_NUMBER CH622KMEB02
J 0
(-3100 4825);
DISPLAY 0.489362 (-3100 4825);
PAINT SKYBLUE (-3100 4825);
FORCEPROP 1 LAST VOLTAGE 4V
J 0
(-3100 4975);
DISPLAY 0.489362 (-3100 4975);
PAINT SKYBLUE (-3100 4975);
FORCEPROP 1 LAST PACK_TYPE C0402
J 0
(-3100 4775);
DISPLAY 0.489362 (-3100 4775);
PAINT SKYBLUE (-3100 4775);
FORCEPROP 2 LAST CDS_LIB pure_quanta
J 0
(-3150 4975);
PAINT MONO (-3150 4975);
DISPLAY INVISIBLE (-3150 4975);
FORCEPROP 1 LAST PATH I54
J 0
(-3100 5125);
DISPLAY 0.978723 (-3100 5125);
PAINT WHITE (-3100 5125);
DISPLAY INVISIBLE (-3100 5125);
FORCEADD UNIVERSAL_POWER..1
(-3600 5250);
FORCEPROP 3 LASTPIN (-3600 5200) SIG_NAME PVDDIO_P1\g
J 0
(-3590 5210);
DISPLAY 0.659574 (-3590 5210);
PAINT MONO (-3590 5210);
DISPLAY INVISIBLE (-3590 5210);
FORCEPROP 1 LAST HDL_POWER PVDDIO_P1
J 1
(-3600 5300);
DISPLAY 0.489362 (-3600 5300);
PAINT GREEN (-3600 5300);
FORCEPROP 2 LAST CDS_LIB pure_quanta_power
J 0
(-3600 5250);
DISPLAY INVISIBLE (-3600 5250);
FORCEPROP 1 LAST PATH I55
J 0
(-3550 5275);
DISPLAY 0.872340 (-3550 5275);
PAINT AQUA (-3550 5275);
DISPLAY INVISIBLE (-3550 5275);
FORCEADD Q_CAP..1
(-2700 4975);
FORCEPROP 1 LAST LOCATION C2270
J 0
(-2650 5075);
DISPLAY 0.489362 (-2650 5075);
PAINT SKYBLUE (-2650 5075);
FORCEPROP 2 LAST $SEC 1
J 0
(-2650 5175);
DISPLAY 0.680851 (-2650 5175);
PAINT MONO (-2650 5175);
DISPLAY INVISIBLE (-2650 5175);
FORCEPROP 2 LAST CDS_SEC 1
J 0
(-2650 5175);
DISPLAY 1.021277 (-2650 5175);
DISPLAY INVISIBLE (-2650 5175);
FORCEPROP 1 LASTPIN (-2700 5075) $PN 1
J 0
(-2690 5055);
DISPLAY 0.489362 (-2690 5055);
FORCEPROP 1 LASTPIN (-2700 4875) $PN 2
J 0
(-2690 4855);
DISPLAY 0.489362 (-2690 4855);
FORCEPROP 1 LAST MATERIAL X6S
J 0
(-2650 4875);
DISPLAY 0.489362 (-2650 4875);
PAINT SKYBLUE (-2650 4875);
FORCEPROP 1 LAST TOLERANCE 20%
J 0
(-2650 4925);
DISPLAY 0.489362 (-2650 4925);
PAINT SKYBLUE (-2650 4925);
FORCEPROP 1 LAST VALUE 22UF
J 0
(-2650 5025);
DISPLAY 0.489362 (-2650 5025);
PAINT SKYBLUE (-2650 5025);
FORCEPROP 1 LAST PART_NUMBER CH622KMEB02
J 0
(-2650 4825);
DISPLAY 0.489362 (-2650 4825);
PAINT SKYBLUE (-2650 4825);
FORCEPROP 1 LAST VOLTAGE 4V
J 0
(-2650 4975);
DISPLAY 0.489362 (-2650 4975);
PAINT SKYBLUE (-2650 4975);
FORCEPROP 1 LAST PACK_TYPE C0402
J 0
(-2650 4775);
DISPLAY 0.489362 (-2650 4775);
PAINT SKYBLUE (-2650 4775);
FORCEPROP 2 LAST CDS_LIB pure_quanta
J 0
(-2700 4975);
PAINT MONO (-2700 4975);
DISPLAY INVISIBLE (-2700 4975);
FORCEPROP 1 LAST PATH I56
J 0
(-2650 5125);
DISPLAY 0.978723 (-2650 5125);
PAINT WHITE (-2650 5125);
DISPLAY INVISIBLE (-2650 5125);
FORCEADD Q_CAP..1
(-2250 4975);
FORCEPROP 1 LAST LOCATION C2274
J 0
(-2200 5075);
DISPLAY 0.489362 (-2200 5075);
PAINT SKYBLUE (-2200 5075);
FORCEPROP 2 LAST $SEC 1
J 0
(-2200 5175);
DISPLAY 0.680851 (-2200 5175);
PAINT MONO (-2200 5175);
DISPLAY INVISIBLE (-2200 5175);
FORCEPROP 2 LAST CDS_SEC 1
J 0
(-2200 5175);
DISPLAY 1.021277 (-2200 5175);
DISPLAY INVISIBLE (-2200 5175);
FORCEPROP 1 LASTPIN (-2250 5075) $PN 1
J 0
(-2240 5055);
DISPLAY 0.489362 (-2240 5055);
FORCEPROP 1 LASTPIN (-2250 4875) $PN 2
J 0
(-2240 4855);
DISPLAY 0.489362 (-2240 4855);
FORCEPROP 1 LAST MATERIAL X6S
J 0
(-2200 4875);
DISPLAY 0.489362 (-2200 4875);
PAINT SKYBLUE (-2200 4875);
FORCEPROP 1 LAST TOLERANCE 20%
J 0
(-2200 4925);
DISPLAY 0.489362 (-2200 4925);
PAINT SKYBLUE (-2200 4925);
FORCEPROP 1 LAST VALUE 22UF
J 0
(-2200 5025);
DISPLAY 0.489362 (-2200 5025);
PAINT SKYBLUE (-2200 5025);
FORCEPROP 1 LAST PART_NUMBER CH622KMEB02
J 0
(-2200 4825);
DISPLAY 0.489362 (-2200 4825);
PAINT SKYBLUE (-2200 4825);
FORCEPROP 1 LAST VOLTAGE 4V
J 0
(-2200 4975);
DISPLAY 0.489362 (-2200 4975);
PAINT SKYBLUE (-2200 4975);
FORCEPROP 1 LAST PACK_TYPE C0402
J 0
(-2200 4775);
DISPLAY 0.489362 (-2200 4775);
PAINT SKYBLUE (-2200 4775);
FORCEPROP 2 LAST CDS_LIB pure_quanta
J 0
(-2250 4975);
PAINT MONO (-2250 4975);
DISPLAY INVISIBLE (-2250 4975);
FORCEPROP 1 LAST PATH I57
J 0
(-2200 5125);
DISPLAY 0.978723 (-2200 5125);
PAINT WHITE (-2200 5125);
DISPLAY INVISIBLE (-2200 5125);
FORCEADD Q_CAP..1
(-1800 4975);
FORCEPROP 1 LAST LOCATION C2278
J 0
(-1750 5075);
DISPLAY 0.489362 (-1750 5075);
PAINT SKYBLUE (-1750 5075);
FORCEPROP 2 LAST $SEC 1
J 0
(-1750 5175);
DISPLAY 0.680851 (-1750 5175);
PAINT MONO (-1750 5175);
DISPLAY INVISIBLE (-1750 5175);
FORCEPROP 2 LAST CDS_SEC 1
J 0
(-1750 5175);
DISPLAY 1.021277 (-1750 5175);
DISPLAY INVISIBLE (-1750 5175);
FORCEPROP 1 LASTPIN (-1800 5075) $PN 1
J 0
(-1790 5055);
DISPLAY 0.489362 (-1790 5055);
FORCEPROP 1 LASTPIN (-1800 4875) $PN 2
J 0
(-1790 4855);
DISPLAY 0.489362 (-1790 4855);
FORCEPROP 1 LAST MATERIAL X6S
J 0
(-1750 4875);
DISPLAY 0.489362 (-1750 4875);
PAINT SKYBLUE (-1750 4875);
FORCEPROP 1 LAST TOLERANCE 20%
J 0
(-1750 4925);
DISPLAY 0.489362 (-1750 4925);
PAINT SKYBLUE (-1750 4925);
FORCEPROP 1 LAST VALUE 22UF
J 0
(-1750 5025);
DISPLAY 0.489362 (-1750 5025);
PAINT SKYBLUE (-1750 5025);
FORCEPROP 1 LAST PART_NUMBER CH622KMEB02
J 0
(-1750 4825);
DISPLAY 0.489362 (-1750 4825);
PAINT SKYBLUE (-1750 4825);
FORCEPROP 1 LAST VOLTAGE 4V
J 0
(-1750 4975);
DISPLAY 0.489362 (-1750 4975);
PAINT SKYBLUE (-1750 4975);
FORCEPROP 1 LAST PACK_TYPE C0402
J 0
(-1750 4775);
DISPLAY 0.489362 (-1750 4775);
PAINT SKYBLUE (-1750 4775);
FORCEPROP 2 LAST CDS_LIB pure_quanta
J 0
(-1800 4975);
PAINT MONO (-1800 4975);
DISPLAY INVISIBLE (-1800 4975);
FORCEPROP 1 LAST PATH I58
J 0
(-1750 5125);
DISPLAY 0.978723 (-1750 5125);
PAINT WHITE (-1750 5125);
DISPLAY INVISIBLE (-1750 5125);
FORCEADD Q_CAP..1
(-1350 4975);
FORCEPROP 1 LAST LOCATION C3910
J 0
(-1300 5075);
DISPLAY 0.489362 (-1300 5075);
PAINT SKYBLUE (-1300 5075);
FORCEPROP 2 LAST $SEC 1
J 0
(-1300 5175);
DISPLAY 0.680851 (-1300 5175);
PAINT MONO (-1300 5175);
DISPLAY INVISIBLE (-1300 5175);
FORCEPROP 2 LAST CDS_SEC 1
J 0
(-1300 5175);
DISPLAY 1.021277 (-1300 5175);
DISPLAY INVISIBLE (-1300 5175);
FORCEPROP 1 LASTPIN (-1350 5075) $PN 1
J 0
(-1340 5055);
DISPLAY 0.489362 (-1340 5055);
FORCEPROP 1 LASTPIN (-1350 4875) $PN 2
J 0
(-1340 4855);
DISPLAY 0.489362 (-1340 4855);
FORCEPROP 1 LAST MATERIAL X6S
J 0
(-1300 4875);
DISPLAY 0.489362 (-1300 4875);
PAINT SKYBLUE (-1300 4875);
FORCEPROP 1 LAST TOLERANCE 20%
J 0
(-1300 4925);
DISPLAY 0.489362 (-1300 4925);
PAINT SKYBLUE (-1300 4925);
FORCEPROP 1 LAST VALUE 22UF
J 0
(-1300 5025);
DISPLAY 0.489362 (-1300 5025);
PAINT SKYBLUE (-1300 5025);
FORCEPROP 1 LAST PART_NUMBER CH622KMEB02
J 0
(-1300 4825);
DISPLAY 0.489362 (-1300 4825);
PAINT SKYBLUE (-1300 4825);
FORCEPROP 1 LAST VOLTAGE 4V
J 0
(-1300 4975);
DISPLAY 0.489362 (-1300 4975);
PAINT SKYBLUE (-1300 4975);
FORCEPROP 1 LAST PACK_TYPE C0402
J 0
(-1300 4775);
DISPLAY 0.489362 (-1300 4775);
PAINT SKYBLUE (-1300 4775);
FORCEPROP 2 LAST CDS_LIB pure_quanta
J 0
(-1350 4975);
PAINT MONO (-1350 4975);
DISPLAY INVISIBLE (-1350 4975);
FORCEPROP 1 LAST PATH I59
J 0
(-1300 5125);
DISPLAY 0.978723 (-1300 5125);
PAINT WHITE (-1300 5125);
DISPLAY INVISIBLE (-1300 5125);
FORCEADD UNIVERSAL_POWER..1
(-8525 3650);
FORCEPROP 3 LASTPIN (-8525 3600) SIG_NAME PVDDCR_SOC_P1\g
J 0
(-8515 3610);
DISPLAY 0.659574 (-8515 3610);
PAINT MONO (-8515 3610);
DISPLAY INVISIBLE (-8515 3610);
FORCEPROP 1 LAST HDL_POWER PVDDCR_SOC_P1
J 1
(-8525 3700);
DISPLAY 0.489362 (-8525 3700);
PAINT GREEN (-8525 3700);
FORCEPROP 2 LAST CDS_LIB pure_quanta_power
J 0
(-8525 3650);
DISPLAY INVISIBLE (-8525 3650);
FORCEPROP 1 LAST PATH I6
J 0
(-8475 3675);
DISPLAY 0.872340 (-8475 3675);
PAINT AQUA (-8475 3675);
DISPLAY INVISIBLE (-8475 3675);
FORCEADD UNIVERSAL_GND..1
(-900 4625);
FORCEPROP 3 LASTPIN (-900 4675) SIG_NAME GND\g
J 0
(-890 4685);
DISPLAY 0.659574 (-890 4685);
PAINT MONO (-890 4685);
DISPLAY INVISIBLE (-890 4685);
FORCEPROP 2 LAST CDS_LIB pure_quanta_power
J 0
(-900 4625);
PAINT MONO (-900 4625);
DISPLAY INVISIBLE (-900 4625);
FORCEPROP 1 LAST PATH I60
J 0
(-825 4625);
DISPLAY 0.872340 (-825 4625);
PAINT AQUA (-825 4625);
DISPLAY INVISIBLE (-825 4625);
FORCEPROP 1 LAST HDL_POWER GND
J 1
(-875 4550);
DISPLAY 0.872340 (-875 4550);
PAINT GREEN (-875 4550);
DISPLAY INVISIBLE (-875 4550);
FORCEADD Q_CAP..1
(-900 4975);
FORCEPROP 1 LAST LOCATION C3911
J 0
(-850 5075);
DISPLAY 0.489362 (-850 5075);
PAINT SKYBLUE (-850 5075);
FORCEPROP 2 LAST $SEC 1
J 0
(-850 5175);
DISPLAY 0.680851 (-850 5175);
PAINT MONO (-850 5175);
DISPLAY INVISIBLE (-850 5175);
FORCEPROP 2 LAST CDS_SEC 1
J 0
(-850 5175);
DISPLAY 1.021277 (-850 5175);
DISPLAY INVISIBLE (-850 5175);
FORCEPROP 1 LASTPIN (-900 5075) $PN 1
J 0
(-890 5055);
DISPLAY 0.489362 (-890 5055);
FORCEPROP 1 LASTPIN (-900 4875) $PN 2
J 0
(-890 4855);
DISPLAY 0.489362 (-890 4855);
FORCEPROP 1 LAST MATERIAL X6S
J 0
(-850 4875);
DISPLAY 0.489362 (-850 4875);
PAINT SKYBLUE (-850 4875);
FORCEPROP 1 LAST TOLERANCE 20%
J 0
(-850 4925);
DISPLAY 0.489362 (-850 4925);
PAINT SKYBLUE (-850 4925);
FORCEPROP 1 LAST VALUE 22UF
J 0
(-850 5025);
DISPLAY 0.489362 (-850 5025);
PAINT SKYBLUE (-850 5025);
FORCEPROP 1 LAST PART_NUMBER CH622KMEB02
J 0
(-850 4825);
DISPLAY 0.489362 (-850 4825);
PAINT SKYBLUE (-850 4825);
FORCEPROP 1 LAST VOLTAGE 4V
J 0
(-850 4975);
DISPLAY 0.489362 (-850 4975);
PAINT SKYBLUE (-850 4975);
FORCEPROP 1 LAST PACK_TYPE C0402
J 0
(-850 4775);
DISPLAY 0.489362 (-850 4775);
PAINT SKYBLUE (-850 4775);
FORCEPROP 2 LAST CDS_LIB pure_quanta
J 0
(-900 4975);
PAINT MONO (-900 4975);
DISPLAY INVISIBLE (-900 4975);
FORCEPROP 1 LAST PATH I61
J 0
(-850 5125);
DISPLAY 0.978723 (-850 5125);
PAINT WHITE (-850 5125);
DISPLAY INVISIBLE (-850 5125);
FORCEADD Q_CAP..1
(-6725 4900);
FORCEPROP 1 LAST LOCATION C2276
J 0
(-6675 5000);
DISPLAY 0.489362 (-6675 5000);
PAINT SKYBLUE (-6675 5000);
FORCEPROP 2 LAST $SEC 1
J 0
(-6675 5100);
DISPLAY 0.680851 (-6675 5100);
PAINT MONO (-6675 5100);
DISPLAY INVISIBLE (-6675 5100);
FORCEPROP 2 LAST CDS_SEC 1
J 0
(-6675 5100);
DISPLAY 1.021277 (-6675 5100);
DISPLAY INVISIBLE (-6675 5100);
FORCEPROP 1 LASTPIN (-6725 5000) $PN 1
J 0
(-6715 4980);
DISPLAY 0.489362 (-6715 4980);
FORCEPROP 1 LASTPIN (-6725 4800) $PN 2
J 0
(-6715 4780);
DISPLAY 0.489362 (-6715 4780);
FORCEPROP 1 LAST MATERIAL X6S
J 0
(-6675 4800);
DISPLAY 0.489362 (-6675 4800);
PAINT SKYBLUE (-6675 4800);
FORCEPROP 1 LAST TOLERANCE 20%
J 0
(-6675 4850);
DISPLAY 0.489362 (-6675 4850);
PAINT SKYBLUE (-6675 4850);
FORCEPROP 1 LAST VALUE 22UF
J 0
(-6675 4950);
DISPLAY 0.489362 (-6675 4950);
PAINT SKYBLUE (-6675 4950);
FORCEPROP 1 LAST PART_NUMBER CH622KMEB02
J 0
(-6675 4750);
DISPLAY 0.489362 (-6675 4750);
PAINT SKYBLUE (-6675 4750);
FORCEPROP 1 LAST VOLTAGE 4V
J 0
(-6675 4900);
DISPLAY 0.489362 (-6675 4900);
PAINT SKYBLUE (-6675 4900);
FORCEPROP 1 LAST PACK_TYPE C0402
J 0
(-6675 4700);
DISPLAY 0.489362 (-6675 4700);
PAINT SKYBLUE (-6675 4700);
FORCEPROP 2 LAST CDS_LIB pure_quanta
J 0
(-6725 4900);
PAINT MONO (-6725 4900);
DISPLAY INVISIBLE (-6725 4900);
FORCEPROP 1 LAST PATH I62
J 0
(-6675 5050);
DISPLAY 0.978723 (-6675 5050);
PAINT WHITE (-6675 5050);
DISPLAY INVISIBLE (-6675 5050);
FORCEADD Q_CAP..1
(-8525 4100);
FORCEPROP 1 LAST LOCATION C2259
J 0
(-8475 4200);
DISPLAY 0.489362 (-8475 4200);
PAINT SKYBLUE (-8475 4200);
FORCEPROP 2 LAST $SEC 1
J 0
(-8475 4300);
DISPLAY 0.680851 (-8475 4300);
PAINT MONO (-8475 4300);
DISPLAY INVISIBLE (-8475 4300);
FORCEPROP 2 LAST CDS_SEC 1
J 0
(-8475 4300);
DISPLAY 1.021277 (-8475 4300);
DISPLAY INVISIBLE (-8475 4300);
FORCEPROP 1 LASTPIN (-8525 4200) $PN 1
J 0
(-8515 4180);
DISPLAY 0.489362 (-8515 4180);
FORCEPROP 1 LASTPIN (-8525 4000) $PN 2
J 0
(-8515 3980);
DISPLAY 0.489362 (-8515 3980);
FORCEPROP 1 LAST MATERIAL X6S
J 0
(-8475 4000);
DISPLAY 0.489362 (-8475 4000);
PAINT SKYBLUE (-8475 4000);
FORCEPROP 1 LAST TOLERANCE 20%
J 0
(-8475 4050);
DISPLAY 0.489362 (-8475 4050);
PAINT SKYBLUE (-8475 4050);
FORCEPROP 1 LAST VALUE 22UF
J 0
(-8475 4150);
DISPLAY 0.489362 (-8475 4150);
PAINT SKYBLUE (-8475 4150);
FORCEPROP 1 LAST PART_NUMBER CH622KMEB02
J 0
(-8475 3950);
DISPLAY 0.489362 (-8475 3950);
PAINT SKYBLUE (-8475 3950);
FORCEPROP 1 LAST VOLTAGE 4V
J 0
(-8475 4100);
DISPLAY 0.489362 (-8475 4100);
PAINT SKYBLUE (-8475 4100);
FORCEPROP 1 LAST PACK_TYPE C0402
J 0
(-8475 3900);
DISPLAY 0.489362 (-8475 3900);
PAINT SKYBLUE (-8475 3900);
FORCEPROP 2 LAST CDS_LIB pure_quanta
J 0
(-8525 4100);
PAINT MONO (-8525 4100);
DISPLAY INVISIBLE (-8525 4100);
FORCEPROP 1 LAST PATH I7
J 0
(-8475 4250);
DISPLAY 0.978723 (-8475 4250);
PAINT WHITE (-8475 4250);
DISPLAY INVISIBLE (-8475 4250);
FORCEADD UNIVERSAL_POWER..1
(-8525 4375);
FORCEPROP 3 LASTPIN (-8525 4325) SIG_NAME PVDDCR_SOC_P1\g
J 0
(-8515 4335);
DISPLAY 0.659574 (-8515 4335);
PAINT MONO (-8515 4335);
DISPLAY INVISIBLE (-8515 4335);
FORCEPROP 1 LAST HDL_POWER PVDDCR_SOC_P1
J 1
(-8525 4425);
DISPLAY 0.489362 (-8525 4425);
PAINT GREEN (-8525 4425);
FORCEPROP 2 LAST CDS_LIB pure_quanta_power
J 0
(-8525 4375);
DISPLAY INVISIBLE (-8525 4375);
FORCEPROP 1 LAST PATH I8
J 0
(-8475 4400);
DISPLAY 0.872340 (-8475 4400);
PAINT AQUA (-8475 4400);
DISPLAY INVISIBLE (-8475 4400);
FORCEADD Q_CAP..1
(-8525 4900);
FORCEPROP 1 LAST LOCATION C2258
J 0
(-8475 5000);
DISPLAY 0.489362 (-8475 5000);
PAINT SKYBLUE (-8475 5000);
FORCEPROP 2 LAST $SEC 1
J 0
(-8475 5100);
DISPLAY 0.680851 (-8475 5100);
PAINT MONO (-8475 5100);
DISPLAY INVISIBLE (-8475 5100);
FORCEPROP 2 LAST CDS_SEC 1
J 0
(-8475 5100);
DISPLAY 1.021277 (-8475 5100);
DISPLAY INVISIBLE (-8475 5100);
FORCEPROP 1 LASTPIN (-8525 5000) $PN 1
J 0
(-8515 4980);
DISPLAY 0.489362 (-8515 4980);
FORCEPROP 1 LASTPIN (-8525 4800) $PN 2
J 0
(-8515 4780);
DISPLAY 0.489362 (-8515 4780);
FORCEPROP 1 LAST MATERIAL X6S
J 0
(-8475 4800);
DISPLAY 0.489362 (-8475 4800);
PAINT SKYBLUE (-8475 4800);
FORCEPROP 1 LAST TOLERANCE 20%
J 0
(-8475 4850);
DISPLAY 0.489362 (-8475 4850);
PAINT SKYBLUE (-8475 4850);
FORCEPROP 1 LAST VALUE 22UF
J 0
(-8475 4950);
DISPLAY 0.489362 (-8475 4950);
PAINT SKYBLUE (-8475 4950);
FORCEPROP 1 LAST PART_NUMBER CH622KMEB02
J 0
(-8475 4750);
DISPLAY 0.489362 (-8475 4750);
PAINT SKYBLUE (-8475 4750);
FORCEPROP 1 LAST VOLTAGE 4V
J 0
(-8475 4900);
DISPLAY 0.489362 (-8475 4900);
PAINT SKYBLUE (-8475 4900);
FORCEPROP 1 LAST PACK_TYPE C0402
J 0
(-8475 4700);
DISPLAY 0.489362 (-8475 4700);
PAINT SKYBLUE (-8475 4700);
FORCEPROP 2 LAST CDS_LIB pure_quanta
J 0
(-8525 4900);
PAINT MONO (-8525 4900);
DISPLAY INVISIBLE (-8525 4900);
FORCEPROP 1 LAST PATH I9
J 0
(-8475 5050);
DISPLAY 0.978723 (-8475 5050);
PAINT WHITE (-8475 5050);
DISPLAY INVISIBLE (-8475 5050);
FORCEADD QUANTA_TITLE_BLOCK_C..1
(225 -500);
FORCEPROP 0 LAST CDS_CON_LAST_MODIFIED Fri Mar 11 14:52:46 2022
J 0
(-1660 -485);
DISPLAY INVISIBLE (-1660 -485);
FORCEPROP 1 LAST CUSTOM_TXT_CDS <CON_LAST_MODIFIED>
J 0
(-1660 -485);
DISPLAY 0.978723 (-1660 -485);
FORCEPROP 2 LAST CUSTOM_TXT_CDS <XR_PAGE_TITLE>
J 0
(-7665 4750);
DISPLAY 0.638298 (-7665 4750);
PAINT PINK (-7665 4750);
DISPLAY INVISIBLE (-7665 4750);
FORCEPROP 1 LAST CUSTOM_TXT_CDS <NAME_2>
J 0
(-2950 -450);
FORCEPROP 1 LAST CUSTOM_TXT_CDS <NAME_1>
J 0
(-2950 -325);
FORCEPROP 1 LAST CUSTOM_TXT_CDS <Q_NUMBER>
J 0
(-1178 -397);
DISPLAY 1.212766 (-1178 -397);
FORCEPROP 1 LAST CUSTOM_TXT_CDS <Q_PROJ>
J 0
(-2157 -398);
DISPLAY 1.212766 (-2157 -398);
FORCEPROP 1 LAST CUSTOM_TXT_CDS <Q_REV>
J 0
(41 -397);
DISPLAY 1.212766 (41 -397);
FORCEPROP 1 LAST CUSTOM_TXT_CDS <CON_PAGE_NUM> OF <CON_TOTAL_PAGES>
J 0
(-221 -482);
DISPLAY 0.978723 (-221 -482);
FORCEPROP 1 LAST Q_DEPT BU9
J 1
(-3538 -451);
DISPLAY 1.957447 (-3538 -451);
PAINT GREEN (-3538 -451);
FORCEPROP 1 LAST Q_TITLE CPU1 CAVITY TOP DECOUPLING CAPS
J 0
(-9141 -474);
DISPLAY 2.446809 (-9141 -474);
PAINT GREEN (-9141 -474);
FORCEPROP 2 LAST CDS_LIB pure_quanta
J 0
(225 -500);
DISPLAY INVISIBLE (225 -500);
FORCEPROP 1 LAST CDS_LMAN_SYM_OUTLINE -9475,6775,100,-125
J 0
(225 -500);
DISPLAY 0.468085 (225 -500);
PAINT GREEN (225 -500);
DISPLAY INVISIBLE (225 -500);
FORCEPROP 2 LAST PAGE_BORDER TRUE
J 0
(-7665 4750);
DISPLAY 0.638298 (-7665 4750);
PAINT PINK (-7665 4750);
DISPLAY INVISIBLE (-7665 4750);
FORCEPROP 1 LAST COMMENT_BODY TRUE
J 0
(237 -513);
DISPLAY 0.978723 (237 -513);
PAINT GREEN (237 -513);
DISPLAY INVISIBLE (237 -513);
FORCEPROP 2 LAST CDS_XR_PAGE_TITLE CR-71 : @T6G_MB_LIB.T6G(SCH_1):PAGE71
J 0
(-7665 4750);
DISPLAY 0.638298 (-7665 4750);
PAINT PINK (-7665 4750);
DISPLAY INVISIBLE (-7665 4750);
WIRE 16 -1 (-4525 5000)(-4525 5075);
WIRE 16 -1 (-4525 5075)(-4925 5075);
WIRE 16 -1 (-4925 5075)(-4925 5000);
WIRE 16 -1 (-4925 5075)(-5375 5075);
WIRE 16 -1 (-5375 5000)(-5375 5075);
WIRE 16 -1 (-5375 5075)(-5825 5075);
WIRE 16 -1 (-5825 5000)(-5825 5075);
WIRE 16 -1 (-5825 5075)(-6275 5075);
WIRE 16 -1 (-6275 5075)(-6275 5000);
WIRE 16 -1 (-6275 5075)(-6725 5075);
WIRE 16 -1 (-6725 5000)(-6725 5075);
WIRE 16 -1 (-6725 5075)(-7175 5075);
WIRE 16 -1 (-7175 5000)(-7175 5075);
WIRE 16 -1 (-7175 5075)(-7625 5075);
WIRE 16 -1 (-7625 5075)(-7625 5000);
WIRE 16 -1 (-7625 5075)(-8075 5075);
WIRE 16 -1 (-8075 5075)(-8525 5075);
WIRE 16 -1 (-8075 5000)(-8075 5075);
WIRE 16 -1 (-8525 5075)(-8525 5125);
WIRE 16 -1 (-8525 5075)(-8525 5000);
WIRE 16 -1 (-8075 4675)(-8525 4675);
WIRE 16 -1 (-7625 4675)(-8075 4675);
WIRE 16 -1 (-8075 4675)(-8075 4800);
WIRE 16 -1 (-8525 4675)(-8525 4800);
WIRE 16 -1 (-7175 4675)(-7625 4675);
WIRE 16 -1 (-7625 4675)(-7625 4800);
WIRE 16 -1 (-6725 4675)(-7175 4675);
WIRE 16 -1 (-7175 4675)(-7175 4800);
WIRE 16 -1 (-6275 4675)(-6725 4675);
WIRE 16 -1 (-6725 4675)(-6725 4800);
WIRE 16 -1 (-5825 4675)(-6275 4675);
WIRE 16 -1 (-6275 4675)(-6275 4800);
WIRE 16 -1 (-5375 4675)(-5825 4675);
WIRE 16 -1 (-5825 4675)(-5825 4800);
WIRE 16 -1 (-4925 4675)(-5375 4675);
WIRE 16 -1 (-5375 4675)(-5375 4800);
WIRE 16 -1 (-4525 4675)(-4925 4675);
WIRE 16 -1 (-4925 4675)(-4925 4800);
WIRE 16 -1 (-4525 4675)(-4525 4800);
WIRE 16 -1 (-4525 4575)(-4525 4675);
WIRE 16 -1 (-4525 4200)(-4525 4275);
WIRE 16 -1 (-4525 4275)(-4925 4275);
WIRE 16 -1 (-4925 4275)(-4925 4200);
WIRE 16 -1 (-4925 4275)(-5375 4275);
WIRE 16 -1 (-5375 4200)(-5375 4275);
WIRE 16 -1 (-5375 4275)(-5825 4275);
WIRE 16 -1 (-5825 4200)(-5825 4275);
WIRE 16 -1 (-5825 4275)(-6275 4275);
WIRE 16 -1 (-6275 4275)(-6275 4200);
WIRE 16 -1 (-6275 4275)(-6725 4275);
WIRE 16 -1 (-6725 4200)(-6725 4275);
WIRE 16 -1 (-6725 4275)(-7175 4275);
WIRE 16 -1 (-7175 4200)(-7175 4275);
WIRE 16 -1 (-7175 4275)(-7625 4275);
WIRE 16 -1 (-7625 4275)(-7625 4200);
WIRE 16 -1 (-7625 4275)(-8075 4275);
WIRE 16 -1 (-8075 4275)(-8525 4275);
WIRE 16 -1 (-8075 4200)(-8075 4275);
WIRE 16 -1 (-8525 4275)(-8525 4325);
WIRE 16 -1 (-8525 4275)(-8525 4200);
WIRE 16 -1 (-8075 3875)(-8525 3875);
WIRE 16 -1 (-7625 3875)(-8075 3875);
WIRE 16 -1 (-8075 3875)(-8075 4000);
WIRE 16 -1 (-8525 3875)(-8525 4000);
WIRE 16 -1 (-7175 3875)(-7625 3875);
WIRE 16 -1 (-7625 3875)(-7625 4000);
WIRE 16 -1 (-6725 3875)(-7175 3875);
WIRE 16 -1 (-7175 3875)(-7175 4000);
WIRE 16 -1 (-6275 3875)(-6725 3875);
WIRE 16 -1 (-6725 3875)(-6725 4000);
WIRE 16 -1 (-5825 3875)(-6275 3875);
WIRE 16 -1 (-6275 3875)(-6275 4000);
WIRE 16 -1 (-5375 3875)(-5825 3875);
WIRE 16 -1 (-5825 3875)(-5825 4000);
WIRE 16 -1 (-4925 3875)(-5375 3875);
WIRE 16 -1 (-5375 3875)(-5375 4000);
WIRE 16 -1 (-4525 3875)(-4925 3875);
WIRE 16 -1 (-4925 3875)(-4925 4000);
WIRE 16 -1 (-4525 3875)(-4525 4000);
WIRE 16 -1 (-4525 3775)(-4525 3875);
WIRE 16 -1 (-4500 1675)(-4500 1750);
WIRE 16 -1 (-4500 1750)(-4900 1750);
WIRE 16 -1 (-4900 1750)(-4900 1675);
WIRE 16 -1 (-4900 1750)(-5350 1750);
WIRE 16 -1 (-5350 1675)(-5350 1750);
WIRE 16 -1 (-5350 1750)(-5800 1750);
WIRE 16 -1 (-5800 1675)(-5800 1750);
WIRE 16 -1 (-5800 1750)(-6250 1750);
WIRE 16 -1 (-6250 1750)(-6250 1675);
WIRE 16 -1 (-6250 1750)(-6700 1750);
WIRE 16 -1 (-6700 1675)(-6700 1750);
WIRE 16 -1 (-6700 1750)(-7150 1750);
WIRE 16 -1 (-7150 1675)(-7150 1750);
WIRE 16 -1 (-7150 1750)(-7600 1750);
WIRE 16 -1 (-7600 1750)(-7600 1675);
WIRE 16 -1 (-7600 1750)(-8050 1750);
WIRE 16 -1 (-8050 1750)(-8500 1750);
WIRE 16 -1 (-8050 1675)(-8050 1750);
WIRE 16 -1 (-8500 1750)(-8500 1800);
WIRE 16 -1 (-8500 1750)(-8500 1675);
WIRE 16 -1 (-8050 1350)(-8500 1350);
WIRE 16 -1 (-7600 1350)(-8050 1350);
WIRE 16 -1 (-8050 1350)(-8050 1475);
WIRE 16 -1 (-8500 1350)(-8500 1475);
WIRE 16 -1 (-7150 1350)(-7600 1350);
WIRE 16 -1 (-7600 1350)(-7600 1475);
WIRE 16 -1 (-6700 1350)(-7150 1350);
WIRE 16 -1 (-7150 1350)(-7150 1475);
WIRE 16 -1 (-6250 1350)(-6700 1350);
WIRE 16 -1 (-6700 1350)(-6700 1475);
WIRE 16 -1 (-5800 1350)(-6250 1350);
WIRE 16 -1 (-6250 1350)(-6250 1475);
WIRE 16 -1 (-5350 1350)(-5800 1350);
WIRE 16 -1 (-5800 1350)(-5800 1475);
WIRE 16 -1 (-4900 1350)(-5350 1350);
WIRE 16 -1 (-5350 1350)(-5350 1475);
WIRE 16 -1 (-4500 1350)(-4900 1350);
WIRE 16 -1 (-4900 1350)(-4900 1475);
WIRE 16 -1 (-4500 1350)(-4500 1475);
WIRE 16 -1 (-4500 1250)(-4500 1350);
WIRE 16 -1 (-8050 1000)(-8500 1000);
WIRE 16 -1 (-7600 1000)(-8050 1000);
WIRE 16 -1 (-8050 925)(-8050 1000);
WIRE 16 -1 (-8500 1000)(-8500 1050);
WIRE 16 -1 (-8500 1000)(-8500 925);
WIRE 16 -1 (-7150 1000)(-7600 1000);
WIRE 16 -1 (-7600 925)(-7600 1000);
WIRE 16 -1 (-6700 1000)(-7150 1000);
WIRE 16 -1 (-7150 925)(-7150 1000);
WIRE 16 -1 (-6250 1000)(-6700 1000);
WIRE 16 -1 (-6700 1000)(-6700 925);
WIRE 16 -1 (-6250 925)(-6250 1000);
WIRE 16 -1 (-8050 600)(-8500 600);
WIRE 16 -1 (-7600 600)(-8050 600);
WIRE 16 -1 (-8050 600)(-8050 725);
WIRE 16 -1 (-8500 600)(-8500 725);
WIRE 16 -1 (-7150 600)(-7600 600);
WIRE 16 -1 (-7600 600)(-7600 725);
WIRE 16 -1 (-6700 600)(-7150 600);
WIRE 16 -1 (-7150 600)(-7150 725);
WIRE 16 -1 (-6250 600)(-6700 600);
WIRE 16 -1 (-6700 600)(-6700 725);
WIRE 16 -1 (-6250 600)(-6250 725);
WIRE 16 -1 (-6250 500)(-6250 600);
WIRE 16 -1 (-8075 3550)(-8525 3550);
WIRE 16 -1 (-8075 3475)(-8075 3550);
WIRE 16 -1 (-8525 3550)(-8525 3600);
WIRE 16 -1 (-8525 3550)(-8525 3475);
WIRE 16 -1 (-8075 3150)(-8525 3150);
WIRE 16 -1 (-8075 3075)(-8075 3150);
WIRE 16 -1 (-8075 3275)(-8075 3150);
WIRE 16 -1 (-8525 3150)(-8525 3275);
WIRE 16 3135 (-8775 400)(-4100 400);
WIRE 16 3135 (-8775 400)(-8775 2175);
WIRE 16 3135 (-4100 400)(-4100 2175);
WIRE 16 3135 (-8775 2175)(-4100 2175);
WIRE 16 3135 (-8775 2700)(-4025 2700);
WIRE 16 3135 (-8775 2700)(-8775 5675);
WIRE 16 3135 (-4025 2700)(-4025 5675);
WIRE 16 3135 (-8775 5675)(-4025 5675);
WIRE 16 -1 (-3150 3550)(-3600 3550);
WIRE 16 -1 (-2700 3550)(-3150 3550);
WIRE 16 -1 (-3150 3475)(-3150 3550);
WIRE 16 -1 (-3600 3550)(-3600 3600);
WIRE 16 -1 (-3600 3550)(-3600 3475);
WIRE 16 -1 (-2700 3475)(-2700 3550);
WIRE 16 -1 (-3150 3150)(-3600 3150);
WIRE 16 -1 (-2700 3150)(-3150 3150);
WIRE 16 -1 (-3150 3275)(-3150 3150);
WIRE 16 -1 (-3600 3150)(-3600 3275);
WIRE 16 -1 (-2700 3075)(-2700 3150);
WIRE 16 -1 (-2700 3275)(-2700 3150);
WIRE 16 3135 (-3900 2900)(-3900 4175);
WIRE 16 3135 (-3900 2900)(-50 2900);
WIRE 16 3135 (-3900 4175)(-50 4175);
WIRE 16 3135 (-50 2900)(-50 4175);
WIRE 16 -1 (-3150 4750)(-3600 4750);
WIRE 16 -1 (-2700 4750)(-3150 4750);
WIRE 16 -1 (-3150 4750)(-3150 4875);
WIRE 16 -1 (-3600 4750)(-3600 4875);
WIRE 16 -1 (-2250 4750)(-2700 4750);
WIRE 16 -1 (-2700 4750)(-2700 4875);
WIRE 16 -1 (-1800 4750)(-2250 4750);
WIRE 16 -1 (-2250 4750)(-2250 4875);
WIRE 16 -1 (-1350 4750)(-1800 4750);
WIRE 16 -1 (-1800 4750)(-1800 4875);
WIRE 16 -1 (-900 4750)(-1350 4750);
WIRE 16 -1 (-1350 4750)(-1350 4875);
WIRE 16 -1 (-900 4675)(-900 4750);
WIRE 16 -1 (-900 4750)(-900 4875);
WIRE 16 -1 (-900 5075)(-900 5150);
WIRE 16 -1 (-900 5150)(-1350 5150);
WIRE 16 -1 (-1350 5075)(-1350 5150);
WIRE 16 -1 (-1350 5150)(-1800 5150);
WIRE 16 -1 (-1800 5075)(-1800 5150);
WIRE 16 -1 (-1800 5150)(-2250 5150);
WIRE 16 -1 (-2250 5075)(-2250 5150);
WIRE 16 -1 (-2250 5150)(-2700 5150);
WIRE 16 -1 (-2700 5150)(-2700 5075);
WIRE 16 -1 (-2700 5150)(-3150 5150);
WIRE 16 -1 (-3150 5150)(-3600 5150);
WIRE 16 -1 (-3150 5075)(-3150 5150);
WIRE 16 -1 (-3600 5150)(-3600 5200);
WIRE 16 -1 (-3600 5150)(-3600 5075);
WIRE 16 3135 (-3875 4500)(-75 4500);
WIRE 16 3135 (-3875 4500)(-3875 5700);
WIRE 16 3135 (-75 4500)(-75 5700);
WIRE 16 3135 (-3875 5700)(-75 5700);
DOT 1 (-1800 5150);
DOT 1 (-8500 1000);
DOT 1 (-8500 1750);
DOT 1 (-8525 3550);
DOT 1 (-8525 4275);
DOT 1 (-8525 5075);
DOT 1 (-8050 600);
DOT 1 (-7600 600);
DOT 1 (-8050 1000);
DOT 1 (-8050 1350);
DOT 1 (-8050 1750);
DOT 1 (-7600 1000);
DOT 1 (-7600 1350);
DOT 1 (-7600 1750);
DOT 1 (-7150 600);
DOT 1 (-6700 600);
DOT 1 (-6250 600);
DOT 1 (-7150 1000);
DOT 1 (-7150 1350);
DOT 1 (-6700 1000);
DOT 1 (-6700 1350);
DOT 1 (-7150 1750);
DOT 1 (-6700 1750);
DOT 1 (-6250 1350);
DOT 1 (-6250 1750);
DOT 1 (-8075 3150);
DOT 1 (-8075 3875);
DOT 1 (-7625 3875);
DOT 1 (-7175 3875);
DOT 1 (-6725 3875);
DOT 1 (-6275 3875);
DOT 1 (-5800 1350);
DOT 1 (-5800 1750);
DOT 1 (-5350 1350);
DOT 1 (-5350 1750);
DOT 1 (-4900 1350);
DOT 1 (-4900 1750);
DOT 1 (-4500 1350);
DOT 1 (-5825 3875);
DOT 1 (-5375 3875);
DOT 1 (-4925 3875);
DOT 1 (-4525 3875);
DOT 1 (-8075 4275);
DOT 1 (-8075 4675);
DOT 1 (-7625 4275);
DOT 1 (-7625 4675);
DOT 1 (-8075 5075);
DOT 1 (-7625 5075);
DOT 1 (-7175 4275);
DOT 1 (-6725 4275);
DOT 1 (-7175 4675);
DOT 1 (-6725 4675);
DOT 1 (-6275 4275);
DOT 1 (-6275 4675);
DOT 1 (-7175 5075);
DOT 1 (-6725 5075);
DOT 1 (-6275 5075);
DOT 1 (-5825 4275);
DOT 1 (-5825 4675);
DOT 1 (-5375 4275);
DOT 1 (-5375 4675);
DOT 1 (-5825 5075);
DOT 1 (-5375 5075);
DOT 1 (-4925 4275);
DOT 1 (-4925 4675);
DOT 1 (-4525 4675);
DOT 1 (-4925 5075);
DOT 1 (-3600 3550);
DOT 1 (-3150 3150);
DOT 1 (-3150 3550);
DOT 1 (-2700 3150);
DOT 1 (-3150 4750);
DOT 1 (-3600 5150);
DOT 1 (-3150 5150);
DOT 1 (-2700 4750);
DOT 1 (-2250 4750);
DOT 1 (-2700 5150);
DOT 1 (-2250 5150);
DOT 1 (-1800 4750);
DOT 1 (-1350 4750);
DOT 1 (-1350 5150);
DOT 1 (-900 4750);
FORCENOTE
PVDD11_S3_P1: 16PCS 22UF ON TOP
(-8525 2000) 0;
DISPLAY LEFT (-8525 2000);
DISPLAY 2.510638 (-8525 2000);
PAINT WHITE (-8525 2000);
FORCENOTE
PVDDCR_SOC_P1: 22PCS 22UF ON TOP
(-8525 5375) 0;
DISPLAY LEFT (-8525 5375);
DISPLAY 2.510638 (-8525 5375);
PAINT WHITE (-8525 5375);
FORCENOTE
5
(-6725 1075) 0;
DISPLAY LEFT (-6725 1075);
DISPLAY 1.021277 (-6725 1075);
PAINT SKYBLUE (-6725 1075);
FORCENOTE
5
(-6725 1850) 0;
DISPLAY LEFT (-6725 1850);
DISPLAY 1.021277 (-6725 1850);
PAINT SKYBLUE (-6725 1850);
FORCENOTE
10
(-4550 1850) 0;
DISPLAY LEFT (-4550 1850);
DISPLAY 1.021277 (-4550 1850);
PAINT SKYBLUE (-4550 1850);
FORCENOTE
5
(-6750 4375) 0;
DISPLAY LEFT (-6750 4375);
DISPLAY 1.021277 (-6750 4375);
PAINT SKYBLUE (-6750 4375);
FORCENOTE
5
(-6750 5175) 0;
DISPLAY LEFT (-6750 5175);
DISPLAY 1.021277 (-6750 5175);
PAINT SKYBLUE (-6750 5175);
FORCENOTE
10
(-4575 4325) 0;
DISPLAY LEFT (-4575 4325);
DISPLAY 1.021277 (-4575 4325);
PAINT SKYBLUE (-4575 4325);
FORCENOTE
10
(-4575 5175) 0;
DISPLAY LEFT (-4575 5175);
DISPLAY 1.021277 (-4575 5175);
PAINT SKYBLUE (-4575 5175);
FORCENOTE
PVDD18_S5_P1: 3PCS 22UF ON TOP
(-3675 3850) 0;
DISPLAY LEFT (-3675 3850);
DISPLAY 2.510638 (-3675 3850);
PAINT WHITE (-3675 3850);
FORCENOTE
5
(-1825 5250) 0;
DISPLAY LEFT (-1825 5250);
DISPLAY 1.021277 (-1825 5250);
PAINT SKYBLUE (-1825 5250);
FORCENOTE
PVDDIO_P1: 7PCS 22UF ON TOP
(-3625 5475) 0;
DISPLAY LEFT (-3625 5475);
DISPLAY 2.510638 (-3625 5475);
PAINT WHITE (-3625 5475);
QUIT
